FILE_TYPE = MACRO_DRAWING;
SET COLOR_WIRE YELLOW;
SET COLOR_PROP ORANGE;
SET COLOR_DOT WHITE;
SET COLOR_ARC YELLOW;
SET COLOR_BODY GREEN;
SET COLOR_NOTE PURPLE;
SET PROP_DISPLAY VALUE;
SET PAGE_NUMBER P170;
FORCEADD 74LVC2G08DP..1
(-1725 750);
FORCEPROP 1 LAST PART_NUMBER ALVC2G08K01
J 0
(-1550 480);
DISPLAY 0.723404 (-1550 480);
PAINT GREEN (-1550 480);
DISPLAY INVISIBLE (-1550 480);
FORCEPROP 2 LAST VALUE 74LVC2G08DP
J 0
(-1545 536);
DISPLAY 0.808511 (-1545 536);
FORCEPROP 2 LAST PART_TYPE SMLF
J 0
(-1550 600);
DISPLAY 0.808511 (-1550 600);
FORCEPROP 1 LAST MATERIAL IC
J 0
(-1550 425);
DISPLAY 0.723404 (-1550 425);
PAINT GREEN (-1550 425);
FORCEPROP 1 LAST $LOCATION U241
J 0
(-1550 650);
DISPLAY 0.723404 (-1550 650);
PAINT GREEN (-1550 650);
FORCEPROP 0 LASTPIN (-2025 800) $PN 1
J 2
(-2035 810);
DISPLAY 0.680851 (-2035 810);
PAINT MONO (-2035 810);
FORCEPROP 0 LASTPIN (-2025 700) $PN 2
J 2
(-2035 710);
DISPLAY 0.680851 (-2035 710);
PAINT MONO (-2035 710);
FORCEPROP 0 LASTPIN (-1425 750) $PN 7
J 0
(-1415 760);
DISPLAY 0.680851 (-1415 760);
PAINT MONO (-1415 760);
FORCEPROP 0 LASTPIN (-1725 600) $PN 4
R 1
J 2
(-1735 590);
DISPLAY 0.680851 (-1735 590);
PAINT MONO (-1735 590);
FORCEPROP 0 LASTPIN (-1725 900) $PN 8
R 1
J 0
(-1735 910);
DISPLAY 0.680851 (-1735 910);
PAINT MONO (-1735 910);
FORCEPROP 1 LAST CDS_LMAN_SYM_OUTLINE -150,100,150,-100
J 0
(-1725 750);
DISPLAY 0.468085 (-1725 750);
PAINT GREEN (-1725 750);
DISPLAY INVISIBLE (-1725 750);
FORCEPROP 1 LAST NEEDS_NO_SIZE TRUE
J 0
(-1725 750);
DISPLAY 0.723404 (-1725 750);
PAINT GREEN (-1725 750);
DISPLAY INVISIBLE (-1725 750);
FORCEPROP 1 LAST PATH I1
J 0
(-1725 750);
DISPLAY 0.723404 (-1725 750);
PAINT GREEN (-1725 750);
DISPLAY INVISIBLE (-1725 750);
FORCEPROP 2 LAST CDS_LIB pure_quanta
J 0
(-1725 750);
DISPLAY INVISIBLE (-1725 750);
FORCEPROP 0 LAST CDS_LOCATION U241
J 0
(-1550 675);
DISPLAY 1.021277 (-1550 675);
DISPLAY INVISIBLE (-1550 675);
FORCEPROP 0 LAST $SEC 1
J 0
(-1550 675);
DISPLAY 0.680851 (-1550 675);
PAINT MONO (-1550 675);
DISPLAY INVISIBLE (-1550 675);
FORCEPROP 0 LAST CDS_SEC 1
J 0
(-1550 675);
DISPLAY 1.021277 (-1550 675);
DISPLAY INVISIBLE (-1550 675);
FORCEADD OFFPAGE..1
(-2750 2800);
FORCEPROP 2 LAST $XR1 156 
J 0
(-3122 2800);
DISPLAY 0.638298 (-3122 2800);
PAINT MONO (-3122 2800);
FORCEPROP 2 LAST $XR0 153 
J 0
(-3002 2800);
DISPLAY 0.638298 (-3002 2800);
PAINT MONO (-3002 2800);
FORCEPROP 2 LAST PATH I10
J 0
(-3000 2850);
DISPLAY 1.021277 (-3000 2850);
DISPLAY INVISIBLE (-3000 2850);
FORCEPROP 2 LAST CDS_LIB standard
J 0
(-2750 2800);
PAINT MONO (-2750 2800);
DISPLAY INVISIBLE (-2750 2800);
FORCEPROP 1 LAST OFFPAGE TRUE
J 0
(-2425 2675);
DISPLAY 0.872340 (-2425 2675);
PAINT GREEN (-2425 2675);
DISPLAY INVISIBLE (-2425 2675);
FORCEPROP 1 LAST COMMENT_BODY TRUE
J 0
(-2625 2700);
DISPLAY 0.872340 (-2625 2700);
PAINT GREEN (-2625 2700);
DISPLAY INVISIBLE (-2625 2700);
FORCEADD 74LVC2G08DP..1
(-1725 2850);
FORCEPROP 1 LAST PART_NUMBER ALVC2G08K01
J 0
(-1575 2605);
DISPLAY 0.723404 (-1575 2605);
PAINT GREEN (-1575 2605);
DISPLAY INVISIBLE (-1575 2605);
FORCEPROP 2 LAST PART_TYPE SMLF
J 0
(-1575 2700);
DISPLAY 0.808511 (-1575 2700);
FORCEPROP 1 LAST MATERIAL IC
J 0
(-1575 2550);
DISPLAY 0.723404 (-1575 2550);
PAINT GREEN (-1575 2550);
FORCEPROP 2 LAST VALUE 74LVC2G08DP
J 0
(-1575 2650);
DISPLAY 0.808511 (-1575 2650);
FORCEPROP 1 LAST $LOCATION U240
J 0
(-1575 2750);
DISPLAY 0.723404 (-1575 2750);
PAINT GREEN (-1575 2750);
FORCEPROP 0 LASTPIN (-2025 2900) $PN 1
J 2
(-2035 2910);
DISPLAY 0.680851 (-2035 2910);
PAINT MONO (-2035 2910);
FORCEPROP 0 LASTPIN (-2025 2800) $PN 2
J 2
(-2035 2810);
DISPLAY 0.680851 (-2035 2810);
PAINT MONO (-2035 2810);
FORCEPROP 0 LASTPIN (-1425 2850) $PN 7
J 0
(-1415 2860);
DISPLAY 0.680851 (-1415 2860);
PAINT MONO (-1415 2860);
FORCEPROP 0 LASTPIN (-1725 2700) $PN 4
R 1
J 2
(-1735 2690);
DISPLAY 0.680851 (-1735 2690);
PAINT MONO (-1735 2690);
FORCEPROP 0 LASTPIN (-1725 3000) $PN 8
R 1
J 0
(-1735 3010);
DISPLAY 0.680851 (-1735 3010);
PAINT MONO (-1735 3010);
FORCEPROP 1 LAST NEEDS_NO_SIZE TRUE
J 0
(-1725 2850);
DISPLAY 0.723404 (-1725 2850);
PAINT GREEN (-1725 2850);
DISPLAY INVISIBLE (-1725 2850);
FORCEPROP 1 LAST CDS_LMAN_SYM_OUTLINE -150,100,150,-100
J 0
(-1725 2850);
DISPLAY 0.468085 (-1725 2850);
PAINT GREEN (-1725 2850);
DISPLAY INVISIBLE (-1725 2850);
FORCEPROP 1 LAST PATH I11
J 0
(-1725 2850);
DISPLAY 0.723404 (-1725 2850);
PAINT GREEN (-1725 2850);
DISPLAY INVISIBLE (-1725 2850);
FORCEPROP 2 LAST CDS_LIB pure_quanta
J 0
(-1725 2850);
DISPLAY INVISIBLE (-1725 2850);
FORCEPROP 0 LAST CDS_LOCATION U240
J 0
(-1550 2775);
DISPLAY 1.021277 (-1550 2775);
DISPLAY INVISIBLE (-1550 2775);
FORCEPROP 0 LAST $SEC 1
J 0
(-1550 2775);
DISPLAY 0.680851 (-1550 2775);
PAINT MONO (-1550 2775);
DISPLAY INVISIBLE (-1550 2775);
FORCEPROP 0 LAST CDS_SEC 1
J 0
(-1550 2775);
DISPLAY 1.021277 (-1550 2775);
DISPLAY INVISIBLE (-1550 2775);
FORCEADD 74LVC2G08DP..2
(-1725 1950);
FORCEPROP 1 LAST PART_NUMBER ALVC2G08K01
J 0
(-1879 2110);
DISPLAY 0.723404 (-1879 2110);
PAINT GREEN (-1879 2110);
DISPLAY INVISIBLE (-1879 2110);
FORCEPROP 2 LAST VALUE 74LVC2G08DP
J 0
(-1875 2150);
DISPLAY 0.808511 (-1875 2150);
FORCEPROP 2 LAST PART_TYPE SMLF
J 0
(-1875 2200);
DISPLAY 0.808511 (-1875 2200);
FORCEPROP 1 LAST MATERIAL IC
J 0
(-1879 2060);
DISPLAY 0.723404 (-1879 2060);
PAINT GREEN (-1879 2060);
FORCEPROP 1 LAST $LOCATION U240
J 0
(-1875 2250);
DISPLAY 0.723404 (-1875 2250);
PAINT GREEN (-1875 2250);
FORCEPROP 0 LASTPIN (-2025 2000) $PN 5
J 2
(-2035 2010);
DISPLAY 0.680851 (-2035 2010);
PAINT MONO (-2035 2010);
FORCEPROP 0 LASTPIN (-2025 1900) $PN 6
J 2
(-2035 1910);
DISPLAY 0.680851 (-2035 1910);
PAINT MONO (-2035 1910);
FORCEPROP 0 LASTPIN (-1425 1950) $PN 3
J 0
(-1415 1960);
DISPLAY 0.680851 (-1415 1960);
PAINT MONO (-1415 1960);
FORCEPROP 2 LAST CDS_LIB pure_quanta
J 0
(-1725 1950);
DISPLAY INVISIBLE (-1725 1950);
FORCEPROP 1 LAST PATH I12
J 0
(-1725 1950);
DISPLAY 0.723404 (-1725 1950);
PAINT GREEN (-1725 1950);
DISPLAY INVISIBLE (-1725 1950);
FORCEPROP 1 LAST CDS_LMAN_SYM_OUTLINE -150,100,150,-100
J 0
(-1725 1950);
DISPLAY 0.468085 (-1725 1950);
PAINT GREEN (-1725 1950);
DISPLAY INVISIBLE (-1725 1950);
FORCEPROP 1 LAST NEEDS_NO_SIZE TRUE
J 0
(-1725 1950);
DISPLAY 0.723404 (-1725 1950);
PAINT GREEN (-1725 1950);
DISPLAY INVISIBLE (-1725 1950);
FORCEPROP 0 LAST CDS_LOCATION U240
J 0
(-1875 2300);
DISPLAY 1.021277 (-1875 2300);
DISPLAY INVISIBLE (-1875 2300);
FORCEPROP 0 LAST $SEC 2
J 0
(-1875 2300);
DISPLAY 0.680851 (-1875 2300);
PAINT MONO (-1875 2300);
DISPLAY INVISIBLE (-1875 2300);
FORCEPROP 0 LAST CDS_SEC 2
J 0
(-1875 2300);
DISPLAY 1.021277 (-1875 2300);
DISPLAY INVISIBLE (-1875 2300);
FORCEADD 74LVC2G08DP..1
(-400 2400);
FORCEPROP 1 LAST PART_NUMBER ALVC2G08K01
J 0
(-675 1975);
DISPLAY 0.723404 (-675 1975);
PAINT GREEN (-675 1975);
DISPLAY INVISIBLE (-675 1975);
FORCEPROP 1 LAST MATERIAL IC
J 0
(-675 2125);
DISPLAY 0.723404 (-675 2125);
PAINT GREEN (-675 2125);
FORCEPROP 2 LAST VALUE 74LVC2G08DP
J 0
(-675 2025);
DISPLAY 0.808511 (-675 2025);
PAINT GREEN (-675 2025);
FORCEPROP 1 LAST $LOCATION U242
J 0
(-675 2075);
DISPLAY 0.723404 (-675 2075);
PAINT GREEN (-675 2075);
FORCEPROP 0 LASTPIN (-700 2450) $PN 1
J 2
(-710 2460);
DISPLAY 0.680851 (-710 2460);
PAINT MONO (-710 2460);
FORCEPROP 0 LASTPIN (-700 2350) $PN 2
J 2
(-710 2360);
DISPLAY 0.680851 (-710 2360);
PAINT MONO (-710 2360);
FORCEPROP 0 LASTPIN (-100 2400) $PN 7
J 0
(-90 2410);
DISPLAY 0.680851 (-90 2410);
PAINT MONO (-90 2410);
FORCEPROP 0 LASTPIN (-400 2250) $PN 4
R 1
J 2
(-410 2240);
DISPLAY 0.680851 (-410 2240);
PAINT MONO (-410 2240);
FORCEPROP 0 LASTPIN (-400 2550) $PN 8
R 1
J 0
(-410 2560);
DISPLAY 0.680851 (-410 2560);
PAINT MONO (-410 2560);
FORCEPROP 0 LAST PART_TYPE SMLF
J 0
(-795 2038);
DISPLAY 1.021277 (-795 2038);
PAINT GREEN (-795 2038);
DISPLAY INVISIBLE (-795 2038);
FORCEPROP 1 LAST NEEDS_NO_SIZE TRUE
J 0
(-400 2400);
DISPLAY 0.723404 (-400 2400);
PAINT GREEN (-400 2400);
DISPLAY INVISIBLE (-400 2400);
FORCEPROP 1 LAST CDS_LMAN_SYM_OUTLINE -150,100,150,-100
J 0
(-400 2400);
DISPLAY 0.468085 (-400 2400);
PAINT GREEN (-400 2400);
DISPLAY INVISIBLE (-400 2400);
FORCEPROP 1 LAST PATH I13
J 0
(-400 2400);
DISPLAY 0.723404 (-400 2400);
PAINT GREEN (-400 2400);
DISPLAY INVISIBLE (-400 2400);
FORCEPROP 2 LAST CDS_LIB pure_quanta
J 0
(-400 2400);
DISPLAY INVISIBLE (-400 2400);
FORCEPROP 0 LAST CDS_LOCATION U242
J 0
(-750 2175);
DISPLAY 1.021277 (-750 2175);
DISPLAY INVISIBLE (-750 2175);
FORCEPROP 0 LAST $SEC 1
J 0
(-750 2175);
DISPLAY 0.680851 (-750 2175);
PAINT MONO (-750 2175);
DISPLAY INVISIBLE (-750 2175);
FORCEPROP 0 LAST CDS_SEC 1
J 0
(-750 2175);
DISPLAY 1.021277 (-750 2175);
DISPLAY INVISIBLE (-750 2175);
FORCEADD 74LVC2G08DP..2
(-400 275);
FORCEPROP 1 LAST PART_NUMBER ALVC2G08K01
J 0
(-554 435);
DISPLAY 0.723404 (-554 435);
PAINT GREEN (-554 435);
DISPLAY INVISIBLE (-554 435);
FORCEPROP 2 LAST PART_TYPE SMLF
J 0
(-550 525);
DISPLAY 0.808511 (-550 525);
FORCEPROP 1 LAST MATERIAL IC
J 0
(-554 385);
DISPLAY 0.723404 (-554 385);
PAINT GREEN (-554 385);
FORCEPROP 2 LAST VALUE 74LVC2G08DP
J 0
(-550 475);
DISPLAY 0.808511 (-550 475);
FORCEPROP 1 LAST $LOCATION U242
J 0
(-550 575);
DISPLAY 0.723404 (-550 575);
PAINT GREEN (-550 575);
FORCEPROP 0 LASTPIN (-700 325) $PN 5
J 2
(-710 335);
DISPLAY 0.680851 (-710 335);
PAINT MONO (-710 335);
FORCEPROP 0 LASTPIN (-700 225) $PN 6
J 2
(-710 235);
DISPLAY 0.680851 (-710 235);
PAINT MONO (-710 235);
FORCEPROP 0 LASTPIN (-100 275) $PN 3
J 0
(-90 285);
DISPLAY 0.680851 (-90 285);
PAINT MONO (-90 285);
FORCEPROP 2 LAST CDS_LIB pure_quanta
J 0
(-400 275);
DISPLAY INVISIBLE (-400 275);
FORCEPROP 1 LAST PATH I14
J 0
(-400 275);
DISPLAY 0.723404 (-400 275);
PAINT GREEN (-400 275);
DISPLAY INVISIBLE (-400 275);
FORCEPROP 1 LAST CDS_LMAN_SYM_OUTLINE -150,100,150,-100
J 0
(-400 275);
DISPLAY 0.468085 (-400 275);
PAINT GREEN (-400 275);
DISPLAY INVISIBLE (-400 275);
FORCEPROP 1 LAST NEEDS_NO_SIZE TRUE
J 0
(-400 275);
DISPLAY 0.723404 (-400 275);
PAINT GREEN (-400 275);
DISPLAY INVISIBLE (-400 275);
FORCEPROP 0 LAST CDS_LOCATION U242
J 0
(-550 625);
DISPLAY 1.021277 (-550 625);
DISPLAY INVISIBLE (-550 625);
FORCEPROP 0 LAST $SEC 2
J 0
(-550 625);
DISPLAY 0.680851 (-550 625);
PAINT MONO (-550 625);
DISPLAY INVISIBLE (-550 625);
FORCEPROP 0 LAST CDS_SEC 2
J 0
(-550 625);
DISPLAY 1.021277 (-550 625);
DISPLAY INVISIBLE (-550 625);
FORCEADD NC7SB3157..1
R 2
(2025 2400);
FORCEPROP 1 LAST PART_NUMBER ALSB3157000
J 2
(2152 2535);
DISPLAY 0.723404 (2152 2535);
PAINT GREEN (2152 2535);
DISPLAY INVISIBLE (2152 2535);
FORCEPROP 1 LAST VALUE NC7SB3157P6X
J 2
(2150 2575);
DISPLAY 0.723404 (2150 2575);
PAINT GREEN (2150 2575);
FORCEPROP 1 LAST MATERIAL EMPTY
J 2
(2152 2480);
DISPLAY 0.723404 (2152 2480);
PAINT RED (2152 2480);
FORCEPROP 1 LAST $LOCATION U243
J 2
(2152 2615);
DISPLAY 0.723404 (2152 2615);
PAINT GREEN (2152 2615);
FORCEPROP 1 LASTPIN (1725 2300) $PN 4
J 2
(1835 2303);
DISPLAY 0.659574 (1835 2303);
PAINT MONO (1835 2303);
FORCEPROP 1 LASTPIN (2325 2300) $PN 3
J 0
(2215 2303);
DISPLAY 0.659574 (2215 2303);
PAINT MONO (2215 2303);
FORCEPROP 1 LASTPIN (2325 2400) $PN 1
J 0
(2215 2403);
DISPLAY 0.659574 (2215 2403);
PAINT MONO (2215 2403);
FORCEPROP 1 LASTPIN (2325 2350) $PN 2
J 0
(2215 2353);
DISPLAY 0.659574 (2215 2353);
PAINT MONO (2215 2353);
FORCEPROP 1 LASTPIN (1725 2400) $PN 6
J 2
(1835 2403);
DISPLAY 0.659574 (1835 2403);
PAINT MONO (1835 2403);
FORCEPROP 1 LASTPIN (1725 2350) $PN 5
J 2
(1835 2353);
DISPLAY 0.659574 (1835 2353);
PAINT MONO (1835 2353);
FORCEPROP 0 LAST PATH I15
J 2
(2150 2775);
DISPLAY 1.021277 (2150 2775);
DISPLAY INVISIBLE (2150 2775);
FORCEPROP 0 LAST MANUF_PN NC7SB3157P6X
J 2
(2200 2775);
DISPLAY 0.808511 (2200 2775);
DISPLAY INVISIBLE (2200 2775);
FORCEPROP 1 LAST PACK_TYPE SMLF
J 2
(2025 2150);
DISPLAY 0.723404 (2025 2150);
PAINT GREEN (2025 2150);
DISPLAY INVISIBLE (2025 2150);
FORCEPROP 1 LAST CDS_LMAN_SYM_OUTLINE -150,50,150,-150
J 2
(2025 2400);
DISPLAY 0.468085 (2025 2400);
PAINT GREEN (2025 2400);
DISPLAY INVISIBLE (2025 2400);
FORCEPROP 2 LAST CDS_LIB pure_quanta
J 2
(2025 2400);
DISPLAY INVISIBLE (2025 2400);
FORCEPROP 0 LAST CDS_LOCATION U243
J 0
(2175 2775);
DISPLAY 1.021277 (2175 2775);
DISPLAY INVISIBLE (2175 2775);
FORCEPROP 0 LAST $SEC 1
J 0
(2175 2775);
DISPLAY 0.680851 (2175 2775);
PAINT MONO (2175 2775);
DISPLAY INVISIBLE (2175 2775);
FORCEPROP 0 LAST CDS_SEC 1
J 0
(2175 2775);
DISPLAY 1.021277 (2175 2775);
DISPLAY INVISIBLE (2175 2775);
FORCEADD NC7SB3157..1
R 2
(2025 1550);
FORCEPROP 1 LAST PART_NUMBER ALSB3157000
J 2
(2150 1675);
DISPLAY 0.723404 (2150 1675);
PAINT GREEN (2150 1675);
DISPLAY INVISIBLE (2150 1675);
FORCEPROP 1 LAST VALUE NC7SB3157P6X
J 2
(2148 1715);
DISPLAY 0.723404 (2148 1715);
PAINT GREEN (2148 1715);
FORCEPROP 1 LAST MATERIAL EMPTY
J 2
(2152 1630);
DISPLAY 0.723404 (2152 1630);
PAINT RED (2152 1630);
FORCEPROP 1 LAST $LOCATION U244
J 2
(2150 1755);
DISPLAY 0.723404 (2150 1755);
PAINT GREEN (2150 1755);
FORCEPROP 1 LASTPIN (1725 1450) $PN 4
J 2
(1835 1453);
DISPLAY 0.659574 (1835 1453);
PAINT MONO (1835 1453);
FORCEPROP 1 LASTPIN (2325 1450) $PN 3
J 0
(2215 1453);
DISPLAY 0.659574 (2215 1453);
PAINT MONO (2215 1453);
FORCEPROP 1 LASTPIN (2325 1550) $PN 1
J 0
(2215 1553);
DISPLAY 0.659574 (2215 1553);
PAINT MONO (2215 1553);
FORCEPROP 1 LASTPIN (2325 1500) $PN 2
J 0
(2215 1503);
DISPLAY 0.659574 (2215 1503);
PAINT MONO (2215 1503);
FORCEPROP 1 LASTPIN (1725 1550) $PN 6
J 2
(1835 1553);
DISPLAY 0.659574 (1835 1553);
PAINT MONO (1835 1553);
FORCEPROP 1 LASTPIN (1725 1500) $PN 5
J 2
(1835 1503);
DISPLAY 0.659574 (1835 1503);
PAINT MONO (1835 1503);
FORCEPROP 0 LAST PATH I16
J 0
(2175 1925);
DISPLAY 1.021277 (2175 1925);
DISPLAY INVISIBLE (2175 1925);
FORCEPROP 2 LAST CDS_LIB pure_quanta
J 0
(2025 1550);
DISPLAY INVISIBLE (2025 1550);
FORCEPROP 1 LAST CDS_LMAN_SYM_OUTLINE -150,50,150,-150
J 2
(2025 1550);
DISPLAY 0.468085 (2025 1550);
PAINT GREEN (2025 1550);
DISPLAY INVISIBLE (2025 1550);
FORCEPROP 0 LAST MANUF_PN NC7SB3157P6X
J 2
(2200 1925);
DISPLAY 0.808511 (2200 1925);
DISPLAY INVISIBLE (2200 1925);
FORCEPROP 1 LAST PACK_TYPE SMLF
J 2
(2025 1300);
DISPLAY 0.723404 (2025 1300);
PAINT GREEN (2025 1300);
DISPLAY INVISIBLE (2025 1300);
FORCEPROP 0 LAST CDS_LOCATION U244
J 0
(2175 1925);
DISPLAY 1.021277 (2175 1925);
DISPLAY INVISIBLE (2175 1925);
FORCEPROP 0 LAST $SEC 1
J 0
(2175 1925);
DISPLAY 0.680851 (2175 1925);
PAINT MONO (2175 1925);
DISPLAY INVISIBLE (2175 1925);
FORCEPROP 0 LAST CDS_SEC 1
J 0
(2175 1925);
DISPLAY 1.021277 (2175 1925);
DISPLAY INVISIBLE (2175 1925);
FORCEADD NC7SB3157..1
R 2
(2200 275);
FORCEPROP 1 LAST PART_NUMBER ALSB3157000
J 2
(2325 395);
DISPLAY 0.723404 (2325 395);
PAINT GREEN (2325 395);
DISPLAY INVISIBLE (2325 395);
FORCEPROP 1 LAST VALUE NC7SB3157P6X
J 2
(2323 435);
DISPLAY 0.723404 (2323 435);
PAINT GREEN (2323 435);
FORCEPROP 1 LAST MATERIAL EMPTY
J 2
(2327 355);
DISPLAY 0.723404 (2327 355);
PAINT RED (2327 355);
FORCEPROP 1 LAST $LOCATION U246
J 2
(2325 475);
DISPLAY 0.723404 (2325 475);
PAINT GREEN (2325 475);
FORCEPROP 1 LASTPIN (1900 175) $PN 4
J 2
(2010 178);
DISPLAY 0.659574 (2010 178);
PAINT MONO (2010 178);
FORCEPROP 1 LASTPIN (2500 175) $PN 3
J 0
(2390 178);
DISPLAY 0.659574 (2390 178);
PAINT MONO (2390 178);
FORCEPROP 1 LASTPIN (2500 275) $PN 1
J 0
(2390 278);
DISPLAY 0.659574 (2390 278);
PAINT MONO (2390 278);
FORCEPROP 1 LASTPIN (2500 225) $PN 2
J 0
(2390 228);
DISPLAY 0.659574 (2390 228);
PAINT MONO (2390 228);
FORCEPROP 1 LASTPIN (1900 275) $PN 6
J 2
(2010 278);
DISPLAY 0.659574 (2010 278);
PAINT MONO (2010 278);
FORCEPROP 1 LASTPIN (1900 225) $PN 5
J 2
(2010 228);
DISPLAY 0.659574 (2010 228);
PAINT MONO (2010 228);
FORCEPROP 0 LAST MANUF_PN NC7SB3157P6X
J 2
(2375 650);
DISPLAY 0.808511 (2375 650);
DISPLAY INVISIBLE (2375 650);
FORCEPROP 1 LAST PACK_TYPE SMLF
J 2
(2200 25);
DISPLAY 0.723404 (2200 25);
PAINT GREEN (2200 25);
DISPLAY INVISIBLE (2200 25);
FORCEPROP 1 LAST CDS_LMAN_SYM_OUTLINE -150,50,150,-150
J 2
(2200 275);
DISPLAY 0.468085 (2200 275);
PAINT GREEN (2200 275);
DISPLAY INVISIBLE (2200 275);
FORCEPROP 2 LAST CDS_LIB pure_quanta
J 0
(2200 275);
DISPLAY INVISIBLE (2200 275);
FORCEPROP 0 LAST PATH I17
J 0
(2350 650);
DISPLAY 1.021277 (2350 650);
DISPLAY INVISIBLE (2350 650);
FORCEPROP 0 LAST CDS_LOCATION U246
J 0
(2350 650);
DISPLAY 1.021277 (2350 650);
DISPLAY INVISIBLE (2350 650);
FORCEPROP 0 LAST $SEC 1
J 0
(2350 650);
DISPLAY 0.680851 (2350 650);
PAINT MONO (2350 650);
DISPLAY INVISIBLE (2350 650);
FORCEPROP 0 LAST CDS_SEC 1
J 0
(2350 650);
DISPLAY 1.021277 (2350 650);
DISPLAY INVISIBLE (2350 650);
FORCEADD NC7SB3157..1
R 2
(2175 -575);
FORCEPROP 1 LAST PART_NUMBER ALSB3157000
J 2
(2300 -425);
DISPLAY 0.723404 (2300 -425);
PAINT GREEN (2300 -425);
DISPLAY INVISIBLE (2300 -425);
FORCEPROP 1 LAST VALUE NC7SB3157P6X
J 2
(2298 -385);
DISPLAY 0.723404 (2298 -385);
PAINT GREEN (2298 -385);
FORCEPROP 1 LAST MATERIAL EMPTY
J 2
(2302 -495);
DISPLAY 0.723404 (2302 -495);
PAINT RED (2302 -495);
FORCEPROP 1 LAST $LOCATION U245
J 2
(2300 -345);
DISPLAY 0.723404 (2300 -345);
PAINT GREEN (2300 -345);
FORCEPROP 1 LASTPIN (1875 -675) $PN 4
J 2
(1985 -672);
DISPLAY 0.659574 (1985 -672);
PAINT MONO (1985 -672);
FORCEPROP 1 LASTPIN (2475 -675) $PN 3
J 0
(2365 -672);
DISPLAY 0.659574 (2365 -672);
PAINT MONO (2365 -672);
FORCEPROP 1 LASTPIN (2475 -575) $PN 1
J 0
(2365 -572);
DISPLAY 0.659574 (2365 -572);
PAINT MONO (2365 -572);
FORCEPROP 1 LASTPIN (2475 -625) $PN 2
J 0
(2365 -622);
DISPLAY 0.659574 (2365 -622);
PAINT MONO (2365 -622);
FORCEPROP 1 LASTPIN (1875 -575) $PN 6
J 2
(1985 -572);
DISPLAY 0.659574 (1985 -572);
PAINT MONO (1985 -572);
FORCEPROP 1 LASTPIN (1875 -625) $PN 5
J 2
(1985 -622);
DISPLAY 0.659574 (1985 -622);
PAINT MONO (1985 -622);
FORCEPROP 0 LAST PATH I18
J 0
(2325 -200);
DISPLAY 1.021277 (2325 -200);
DISPLAY INVISIBLE (2325 -200);
FORCEPROP 0 LAST MANUF_PN NC7SB3157P6X
J 2
(2350 -200);
DISPLAY 0.808511 (2350 -200);
DISPLAY INVISIBLE (2350 -200);
FORCEPROP 1 LAST PACK_TYPE SMLF
J 2
(2175 -825);
DISPLAY 0.723404 (2175 -825);
PAINT GREEN (2175 -825);
DISPLAY INVISIBLE (2175 -825);
FORCEPROP 1 LAST CDS_LMAN_SYM_OUTLINE -150,50,150,-150
J 2
(2175 -575);
DISPLAY 0.468085 (2175 -575);
PAINT GREEN (2175 -575);
DISPLAY INVISIBLE (2175 -575);
FORCEPROP 2 LAST CDS_LIB pure_quanta
J 0
(2175 -575);
DISPLAY INVISIBLE (2175 -575);
FORCEPROP 0 LAST CDS_LOCATION U245
J 0
(2325 -200);
DISPLAY 1.021277 (2325 -200);
DISPLAY INVISIBLE (2325 -200);
FORCEPROP 0 LAST $SEC 1
J 0
(2325 -200);
DISPLAY 0.680851 (2325 -200);
PAINT MONO (2325 -200);
DISPLAY INVISIBLE (2325 -200);
FORCEPROP 0 LAST CDS_SEC 1
J 0
(2325 -200);
DISPLAY 1.021277 (2325 -200);
DISPLAY INVISIBLE (2325 -200);
FORCEADD UNIVERSAL_GND..1
(-1500 950);
FORCEPROP 3 LASTPIN (-1500 1000) SIG_NAME GND\g
J 0
(-1490 1010);
DISPLAY 0.659574 (-1490 1010);
PAINT MONO (-1490 1010);
DISPLAY INVISIBLE (-1490 1010);
FORCEPROP 2 LAST CDS_LIB logical_power
J 0
(-1500 950);
DISPLAY INVISIBLE (-1500 950);
FORCEPROP 1 LAST PATH I19
J 0
(-1425 950);
DISPLAY 0.872340 (-1425 950);
PAINT AQUA (-1425 950);
DISPLAY INVISIBLE (-1425 950);
FORCEPROP 1 LAST HDL_POWER GND
J 1
(-1475 875);
DISPLAY 0.872340 (-1475 875);
PAINT GREEN (-1475 875);
DISPLAY INVISIBLE (-1475 875);
FORCEADD 74LVC2G08DP..2
(-1725 -150);
FORCEPROP 1 LAST PART_NUMBER ALVC2G08K01
J 0
(-1879 10);
DISPLAY 0.723404 (-1879 10);
PAINT GREEN (-1879 10);
DISPLAY INVISIBLE (-1879 10);
FORCEPROP 2 LAST PART_TYPE SMLF
J 0
(-1875 100);
DISPLAY 0.808511 (-1875 100);
FORCEPROP 2 LAST VALUE 74LVC2G08DP
J 0
(-1875 50);
DISPLAY 0.808511 (-1875 50);
FORCEPROP 1 LAST MATERIAL IC
J 0
(-1879 -40);
DISPLAY 0.723404 (-1879 -40);
PAINT GREEN (-1879 -40);
FORCEPROP 1 LAST $LOCATION U241
J 0
(-1875 150);
DISPLAY 0.723404 (-1875 150);
PAINT GREEN (-1875 150);
FORCEPROP 0 LASTPIN (-2025 -100) $PN 5
J 2
(-2035 -90);
DISPLAY 0.680851 (-2035 -90);
PAINT MONO (-2035 -90);
FORCEPROP 0 LASTPIN (-2025 -200) $PN 6
J 2
(-2035 -190);
DISPLAY 0.680851 (-2035 -190);
PAINT MONO (-2035 -190);
FORCEPROP 0 LASTPIN (-1425 -150) $PN 3
J 0
(-1415 -140);
DISPLAY 0.680851 (-1415 -140);
PAINT MONO (-1415 -140);
FORCEPROP 2 LAST CDS_LIB pure_quanta
J 0
(-1725 -150);
DISPLAY INVISIBLE (-1725 -150);
FORCEPROP 1 LAST PATH I2
J 0
(-1725 -150);
DISPLAY 0.723404 (-1725 -150);
PAINT GREEN (-1725 -150);
DISPLAY INVISIBLE (-1725 -150);
FORCEPROP 1 LAST NEEDS_NO_SIZE TRUE
J 0
(-1725 -150);
DISPLAY 0.723404 (-1725 -150);
PAINT GREEN (-1725 -150);
DISPLAY INVISIBLE (-1725 -150);
FORCEPROP 1 LAST CDS_LMAN_SYM_OUTLINE -150,100,150,-100
J 0
(-1725 -150);
DISPLAY 0.468085 (-1725 -150);
PAINT GREEN (-1725 -150);
DISPLAY INVISIBLE (-1725 -150);
FORCEPROP 0 LAST CDS_LOCATION U241
J 0
(-1875 200);
DISPLAY 1.021277 (-1875 200);
DISPLAY INVISIBLE (-1875 200);
FORCEPROP 0 LAST $SEC 2
J 0
(-1875 200);
DISPLAY 0.680851 (-1875 200);
PAINT MONO (-1875 200);
DISPLAY INVISIBLE (-1875 200);
FORCEPROP 0 LAST CDS_SEC 2
J 0
(-1875 200);
DISPLAY 1.021277 (-1875 200);
DISPLAY INVISIBLE (-1875 200);
FORCEADD UNIVERSAL_POWER..1
(-1500 1500);
FORCEPROP 3 LASTPIN (-1500 1450) SIG_NAME P3V3_AUX\g
J 0
(-1490 1460);
DISPLAY 0.659574 (-1490 1460);
PAINT MONO (-1490 1460);
DISPLAY INVISIBLE (-1490 1460);
FORCEPROP 1 LAST HDL_POWER P3V3_AUX
J 1
(-1500 1550);
DISPLAY 0.872340 (-1500 1550);
PAINT GREEN (-1500 1550);
FORCEPROP 2 LAST CDS_LIB logical_power
J 0
(-1500 1500);
DISPLAY INVISIBLE (-1500 1500);
FORCEPROP 1 LAST PATH I20
J 0
(-1450 1525);
DISPLAY 0.872340 (-1450 1525);
PAINT AQUA (-1450 1525);
DISPLAY INVISIBLE (-1450 1525);
FORCEADD Q_CAP..1
(-1500 1175);
FORCEPROP 1 LAST PART_NUMBER CH4104K1B00
J 0
(-1450 1025);
DISPLAY 0.510638 (-1450 1025);
DISPLAY INVISIBLE (-1450 1025);
FORCEPROP 1 LAST PACK_TYPE 0402
J 0
(-1450 975);
DISPLAY 0.510638 (-1450 975);
FORCEPROP 1 LAST VALUE 0.1UF
J 0
(-1450 1225);
DISPLAY 0.510638 (-1450 1225);
FORCEPROP 1 LAST VOLTAGE 25V
J 0
(-1450 1175);
DISPLAY 0.510638 (-1450 1175);
FORCEPROP 1 LAST TOLERANCE 10%
J 0
(-1450 1125);
DISPLAY 0.510638 (-1450 1125);
FORCEPROP 1 LAST MATERIAL X7R
J 0
(-1450 1075);
DISPLAY 0.510638 (-1450 1075);
FORCEPROP 1 LAST $LOCATION C1875
J 0
(-1450 1275);
DISPLAY 0.978723 (-1450 1275);
FORCEPROP 1 LASTPIN (-1500 1275) $PN 1
J 0
(-1490 1255);
DISPLAY 0.787234 (-1490 1255);
PAINT MONO (-1490 1255);
FORCEPROP 1 LASTPIN (-1500 1075) $PN 2
J 0
(-1490 1055);
DISPLAY 0.787234 (-1490 1055);
PAINT MONO (-1490 1055);
FORCEPROP 2 LAST CDS_LIB pure_quanta
J 0
(-1500 1175);
DISPLAY INVISIBLE (-1500 1175);
FORCEPROP 1 LAST PATH I21
J 0
(-1450 1325);
DISPLAY 0.978723 (-1450 1325);
PAINT WHITE (-1450 1325);
DISPLAY INVISIBLE (-1450 1325);
FORCEPROP 0 LAST CDS_LOCATION C1875
J 0
(-1450 1325);
DISPLAY 1.021277 (-1450 1325);
DISPLAY INVISIBLE (-1450 1325);
FORCEPROP 0 LAST $SEC 1
J 0
(-1450 1325);
DISPLAY 0.680851 (-1450 1325);
PAINT MONO (-1450 1325);
DISPLAY INVISIBLE (-1450 1325);
FORCEPROP 0 LAST CDS_SEC 1
J 0
(-1450 1325);
DISPLAY 1.021277 (-1450 1325);
DISPLAY INVISIBLE (-1450 1325);
FORCEADD Q_CAP..1
(-1600 3250);
FORCEPROP 1 LAST PART_NUMBER CH4104K1B00
J 0
(-1550 3100);
DISPLAY 0.510638 (-1550 3100);
DISPLAY INVISIBLE (-1550 3100);
FORCEPROP 1 LAST VOLTAGE 25V
J 0
(-1550 3250);
DISPLAY 0.510638 (-1550 3250);
FORCEPROP 1 LAST TOLERANCE 10%
J 0
(-1550 3200);
DISPLAY 0.510638 (-1550 3200);
FORCEPROP 1 LAST MATERIAL X7R
J 0
(-1550 3150);
DISPLAY 0.510638 (-1550 3150);
FORCEPROP 1 LAST VALUE 0.1UF
J 0
(-1550 3300);
DISPLAY 0.510638 (-1550 3300);
FORCEPROP 1 LAST PACK_TYPE 0402
J 0
(-1550 3050);
DISPLAY 0.510638 (-1550 3050);
FORCEPROP 1 LAST $LOCATION C1874
J 0
(-1550 3350);
DISPLAY 0.978723 (-1550 3350);
FORCEPROP 1 LASTPIN (-1600 3350) $PN 1
J 0
(-1590 3330);
DISPLAY 0.787234 (-1590 3330);
PAINT MONO (-1590 3330);
FORCEPROP 1 LASTPIN (-1600 3150) $PN 2
J 0
(-1590 3130);
DISPLAY 0.787234 (-1590 3130);
PAINT MONO (-1590 3130);
FORCEPROP 2 LAST CDS_LIB pure_quanta
J 0
(-1600 3250);
DISPLAY INVISIBLE (-1600 3250);
FORCEPROP 1 LAST PATH I22
J 0
(-1550 3400);
DISPLAY 0.978723 (-1550 3400);
PAINT WHITE (-1550 3400);
DISPLAY INVISIBLE (-1550 3400);
FORCEPROP 0 LAST CDS_LOCATION C1874
J 0
(-1550 3400);
DISPLAY 1.021277 (-1550 3400);
DISPLAY INVISIBLE (-1550 3400);
FORCEPROP 0 LAST $SEC 1
J 0
(-1550 3400);
DISPLAY 0.680851 (-1550 3400);
PAINT MONO (-1550 3400);
DISPLAY INVISIBLE (-1550 3400);
FORCEPROP 0 LAST CDS_SEC 1
J 0
(-1550 3400);
DISPLAY 1.021277 (-1550 3400);
DISPLAY INVISIBLE (-1550 3400);
FORCEADD UNIVERSAL_POWER..1
(-1600 3575);
FORCEPROP 3 LASTPIN (-1600 3525) SIG_NAME P3V3_AUX\g
J 0
(-1590 3535);
DISPLAY 0.659574 (-1590 3535);
PAINT MONO (-1590 3535);
DISPLAY INVISIBLE (-1590 3535);
FORCEPROP 1 LAST HDL_POWER P3V3_AUX
J 1
(-1600 3625);
DISPLAY 0.872340 (-1600 3625);
PAINT GREEN (-1600 3625);
FORCEPROP 2 LAST CDS_LIB logical_power
J 0
(-1600 3575);
DISPLAY INVISIBLE (-1600 3575);
FORCEPROP 1 LAST PATH I23
J 0
(-1550 3600);
DISPLAY 0.872340 (-1550 3600);
PAINT AQUA (-1550 3600);
DISPLAY INVISIBLE (-1550 3600);
FORCEADD UNIVERSAL_GND..1
(-1600 3025);
FORCEPROP 3 LASTPIN (-1600 3075) SIG_NAME GND\g
J 0
(-1590 3085);
DISPLAY 0.659574 (-1590 3085);
PAINT MONO (-1590 3085);
DISPLAY INVISIBLE (-1590 3085);
FORCEPROP 2 LAST CDS_LIB logical_power
J 0
(-1600 3025);
DISPLAY INVISIBLE (-1600 3025);
FORCEPROP 1 LAST PATH I24
J 0
(-1525 3025);
DISPLAY 0.872340 (-1525 3025);
PAINT AQUA (-1525 3025);
DISPLAY INVISIBLE (-1525 3025);
FORCEPROP 1 LAST HDL_POWER GND
J 1
(-1575 2950);
DISPLAY 0.872340 (-1575 2950);
PAINT GREEN (-1575 2950);
DISPLAY INVISIBLE (-1575 2950);
FORCEADD UNIVERSAL_GND..1
(-1725 2575);
FORCEPROP 3 LASTPIN (-1725 2625) SIG_NAME GND\g
J 0
(-1715 2635);
DISPLAY 0.659574 (-1715 2635);
PAINT MONO (-1715 2635);
DISPLAY INVISIBLE (-1715 2635);
FORCEPROP 1 LAST HDL_POWER GND
J 1
(-1700 2500);
DISPLAY 0.872340 (-1700 2500);
PAINT GREEN (-1700 2500);
DISPLAY INVISIBLE (-1700 2500);
FORCEPROP 1 LAST PATH I25
J 0
(-1650 2575);
DISPLAY 0.872340 (-1650 2575);
PAINT AQUA (-1650 2575);
DISPLAY INVISIBLE (-1650 2575);
FORCEPROP 2 LAST CDS_LIB logical_power
J 0
(-1725 2575);
DISPLAY INVISIBLE (-1725 2575);
FORCEADD UNIVERSAL_GND..1
(-1725 475);
FORCEPROP 3 LASTPIN (-1725 525) SIG_NAME GND\g
J 0
(-1715 535);
DISPLAY 0.659574 (-1715 535);
PAINT MONO (-1715 535);
DISPLAY INVISIBLE (-1715 535);
FORCEPROP 2 LAST CDS_LIB logical_power
J 0
(-1725 475);
DISPLAY INVISIBLE (-1725 475);
FORCEPROP 1 LAST PATH I26
J 0
(-1650 475);
DISPLAY 0.872340 (-1650 475);
PAINT AQUA (-1650 475);
DISPLAY INVISIBLE (-1650 475);
FORCEPROP 1 LAST HDL_POWER GND
J 1
(-1700 400);
DISPLAY 0.872340 (-1700 400);
PAINT GREEN (-1700 400);
DISPLAY INVISIBLE (-1700 400);
FORCEADD Q_CAP..1
(1525 575);
FORCEPROP 1 LAST PART_NUMBER CH4104K1B00
J 0
(1575 425);
DISPLAY 0.510638 (1575 425);
DISPLAY INVISIBLE (1575 425);
FORCEPROP 1 LAST MATERIAL X7R
J 0
(1575 475);
DISPLAY 0.510638 (1575 475);
FORCEPROP 1 LAST TOLERANCE 10%
J 0
(1575 525);
DISPLAY 0.510638 (1575 525);
FORCEPROP 1 LAST VOLTAGE 25V
J 0
(1575 575);
DISPLAY 0.510638 (1575 575);
FORCEPROP 1 LAST PACK_TYPE 0402
J 0
(1575 375);
DISPLAY 0.510638 (1575 375);
FORCEPROP 1 LAST VALUE 0.1UF
J 0
(1575 625);
DISPLAY 0.510638 (1575 625);
FORCEPROP 1 LAST $LOCATION C1880
J 0
(1575 675);
DISPLAY 0.638298 (1575 675);
FORCEPROP 1 LASTPIN (1525 675) $PN 1
J 0
(1535 655);
DISPLAY 0.787234 (1535 655);
PAINT MONO (1535 655);
FORCEPROP 1 LASTPIN (1525 475) $PN 2
J 0
(1535 455);
DISPLAY 0.787234 (1535 455);
PAINT MONO (1535 455);
FORCEPROP 1 LAST PATH I27
J 0
(1575 725);
DISPLAY 0.978723 (1575 725);
PAINT WHITE (1575 725);
DISPLAY INVISIBLE (1575 725);
FORCEPROP 2 LAST CDS_LIB pure_quanta
J 0
(1525 575);
DISPLAY INVISIBLE (1525 575);
FORCEPROP 0 LAST CDS_LOCATION C1880
J 0
(1575 725);
DISPLAY 1.021277 (1575 725);
DISPLAY INVISIBLE (1575 725);
FORCEPROP 0 LAST $SEC 1
J 0
(1575 725);
DISPLAY 0.680851 (1575 725);
PAINT MONO (1575 725);
DISPLAY INVISIBLE (1575 725);
FORCEPROP 0 LAST CDS_SEC 1
J 0
(1575 725);
DISPLAY 1.021277 (1575 725);
DISPLAY INVISIBLE (1575 725);
FORCEADD UNIVERSAL_GND..1
(1525 350);
FORCEPROP 3 LASTPIN (1525 400) SIG_NAME GND\g
J 0
(1535 410);
DISPLAY 0.659574 (1535 410);
PAINT MONO (1535 410);
DISPLAY INVISIBLE (1535 410);
FORCEPROP 1 LAST HDL_POWER GND
J 1
(1550 275);
DISPLAY 0.872340 (1550 275);
PAINT GREEN (1550 275);
DISPLAY INVISIBLE (1550 275);
FORCEPROP 1 LAST PATH I28
J 0
(1600 350);
DISPLAY 0.872340 (1600 350);
PAINT AQUA (1600 350);
DISPLAY INVISIBLE (1600 350);
FORCEPROP 2 LAST CDS_LIB logical_power
J 0
(1525 350);
DISPLAY INVISIBLE (1525 350);
FORCEADD UNIVERSAL_POWER..1
(1525 900);
FORCEPROP 3 LASTPIN (1525 850) SIG_NAME P3V3_AUX\g
J 0
(1535 860);
DISPLAY 0.659574 (1535 860);
PAINT MONO (1535 860);
DISPLAY INVISIBLE (1535 860);
FORCEPROP 1 LAST HDL_POWER P3V3_AUX
J 1
(1525 950);
DISPLAY 0.872340 (1525 950);
PAINT GREEN (1525 950);
FORCEPROP 1 LAST PATH I29
J 0
(1575 925);
DISPLAY 0.872340 (1575 925);
PAINT AQUA (1575 925);
DISPLAY INVISIBLE (1575 925);
FORCEPROP 2 LAST CDS_LIB logical_power
J 0
(1525 900);
DISPLAY INVISIBLE (1525 900);
FORCEADD OFFPAGE..1
(-2725 800);
FORCEPROP 2 LAST $XR1 162 
J 0
(-3127 800);
DISPLAY 0.638298 (-3127 800);
PAINT MONO (-3127 800);
FORCEPROP 2 LAST $XR0 159 
J 0
(-3007 800);
DISPLAY 0.638298 (-3007 800);
PAINT MONO (-3007 800);
FORCEPROP 2 LAST CDS_LIB standard
J 0
(-2725 800);
PAINT MONO (-2725 800);
DISPLAY INVISIBLE (-2725 800);
FORCEPROP 1 LAST OFFPAGE TRUE
J 0
(-2400 675);
DISPLAY 0.872340 (-2400 675);
PAINT GREEN (-2400 675);
DISPLAY INVISIBLE (-2400 675);
FORCEPROP 1 LAST COMMENT_BODY TRUE
J 0
(-2600 700);
DISPLAY 0.872340 (-2600 700);
PAINT GREEN (-2600 700);
DISPLAY INVISIBLE (-2600 700);
FORCEPROP 2 LAST PATH I3
J 0
(-3000 850);
DISPLAY 1.021277 (-3000 850);
DISPLAY INVISIBLE (-3000 850);
FORCEADD UNIVERSAL_POWER..1
(1525 25);
FORCEPROP 3 LASTPIN (1525 -25) SIG_NAME P3V3_AUX\g
J 0
(1535 -15);
DISPLAY 0.659574 (1535 -15);
PAINT MONO (1535 -15);
DISPLAY INVISIBLE (1535 -15);
FORCEPROP 1 LAST HDL_POWER P3V3_AUX
J 1
(1525 75);
DISPLAY 0.872340 (1525 75);
PAINT GREEN (1525 75);
FORCEPROP 2 LAST CDS_LIB logical_power
J 0
(1525 25);
DISPLAY INVISIBLE (1525 25);
FORCEPROP 1 LAST PATH I30
J 0
(1575 50);
DISPLAY 0.872340 (1575 50);
PAINT AQUA (1575 50);
DISPLAY INVISIBLE (1575 50);
FORCEADD Q_CAP..1
(1525 -250);
FORCEPROP 1 LAST PART_NUMBER CH4104K1B00
J 0
(1575 -400);
DISPLAY 0.510638 (1575 -400);
DISPLAY INVISIBLE (1575 -400);
FORCEPROP 1 LAST VOLTAGE 25V
J 0
(1575 -250);
DISPLAY 0.510638 (1575 -250);
FORCEPROP 1 LAST PACK_TYPE 0402
J 0
(1575 -450);
DISPLAY 0.510638 (1575 -450);
FORCEPROP 1 LAST MATERIAL X7R
J 0
(1575 -350);
DISPLAY 0.510638 (1575 -350);
FORCEPROP 1 LAST TOLERANCE 10%
J 0
(1575 -300);
DISPLAY 0.510638 (1575 -300);
FORCEPROP 1 LAST VALUE 0.1UF
J 0
(1575 -200);
DISPLAY 0.510638 (1575 -200);
FORCEPROP 1 LAST $LOCATION C1879
J 0
(1575 -150);
DISPLAY 0.638298 (1575 -150);
FORCEPROP 1 LASTPIN (1525 -150) $PN 1
J 0
(1535 -170);
DISPLAY 0.787234 (1535 -170);
PAINT MONO (1535 -170);
FORCEPROP 1 LASTPIN (1525 -350) $PN 2
J 0
(1535 -370);
DISPLAY 0.787234 (1535 -370);
PAINT MONO (1535 -370);
FORCEPROP 2 LAST CDS_LIB pure_quanta
J 0
(1525 -250);
DISPLAY INVISIBLE (1525 -250);
FORCEPROP 1 LAST PATH I31
J 0
(1575 -100);
DISPLAY 0.978723 (1575 -100);
PAINT WHITE (1575 -100);
DISPLAY INVISIBLE (1575 -100);
FORCEPROP 0 LAST CDS_LOCATION C1879
J 0
(1575 -100);
DISPLAY 1.021277 (1575 -100);
DISPLAY INVISIBLE (1575 -100);
FORCEPROP 0 LAST $SEC 1
J 0
(1575 -100);
DISPLAY 0.680851 (1575 -100);
PAINT MONO (1575 -100);
DISPLAY INVISIBLE (1575 -100);
FORCEPROP 0 LAST CDS_SEC 1
J 0
(1575 -100);
DISPLAY 1.021277 (1575 -100);
DISPLAY INVISIBLE (1575 -100);
FORCEADD UNIVERSAL_GND..1
(1525 -475);
FORCEPROP 3 LASTPIN (1525 -425) SIG_NAME GND\g
J 0
(1535 -415);
DISPLAY 0.659574 (1535 -415);
PAINT MONO (1535 -415);
DISPLAY INVISIBLE (1535 -415);
FORCEPROP 2 LAST CDS_LIB logical_power
J 0
(1525 -475);
DISPLAY INVISIBLE (1525 -475);
FORCEPROP 1 LAST PATH I32
J 0
(1600 -475);
DISPLAY 0.872340 (1600 -475);
PAINT AQUA (1600 -475);
DISPLAY INVISIBLE (1600 -475);
FORCEPROP 1 LAST HDL_POWER GND
J 1
(1550 -550);
DISPLAY 0.872340 (1550 -550);
PAINT GREEN (1550 -550);
DISPLAY INVISIBLE (1550 -550);
FORCEADD UNIVERSAL_POWER..1
(1325 3100);
FORCEPROP 3 LASTPIN (1325 3050) SIG_NAME P3V3_AUX\g
J 0
(1335 3060);
DISPLAY 0.659574 (1335 3060);
PAINT MONO (1335 3060);
DISPLAY INVISIBLE (1335 3060);
FORCEPROP 1 LAST HDL_POWER P3V3_AUX
J 1
(1325 3150);
DISPLAY 0.872340 (1325 3150);
PAINT GREEN (1325 3150);
FORCEPROP 1 LAST PATH I33
J 0
(1375 3125);
DISPLAY 0.872340 (1375 3125);
PAINT AQUA (1375 3125);
DISPLAY INVISIBLE (1375 3125);
FORCEPROP 2 LAST CDS_LIB logical_power
J 0
(1325 3100);
DISPLAY INVISIBLE (1325 3100);
FORCEADD Q_CAP..1
(1325 2775);
FORCEPROP 1 LAST PART_NUMBER CH4104K1B00
J 0
(1375 2625);
DISPLAY 0.510638 (1375 2625);
DISPLAY INVISIBLE (1375 2625);
FORCEPROP 1 LAST MATERIAL X7R
J 0
(1375 2675);
DISPLAY 0.510638 (1375 2675);
FORCEPROP 1 LAST TOLERANCE 10%
J 0
(1375 2725);
DISPLAY 0.510638 (1375 2725);
FORCEPROP 1 LAST VOLTAGE 25V
J 0
(1375 2775);
DISPLAY 0.510638 (1375 2775);
FORCEPROP 1 LAST VALUE 0.1UF
J 0
(1375 2825);
DISPLAY 0.510638 (1375 2825);
FORCEPROP 1 LAST PACK_TYPE 0402
J 0
(1375 2575);
DISPLAY 0.510638 (1375 2575);
FORCEPROP 1 LAST $LOCATION C1877
J 0
(1375 2875);
DISPLAY 0.638298 (1375 2875);
FORCEPROP 1 LASTPIN (1325 2875) $PN 1
J 0
(1335 2855);
DISPLAY 0.787234 (1335 2855);
PAINT MONO (1335 2855);
FORCEPROP 1 LASTPIN (1325 2675) $PN 2
J 0
(1335 2655);
DISPLAY 0.787234 (1335 2655);
PAINT MONO (1335 2655);
FORCEPROP 1 LAST PATH I34
J 0
(1375 2925);
DISPLAY 0.978723 (1375 2925);
PAINT WHITE (1375 2925);
DISPLAY INVISIBLE (1375 2925);
FORCEPROP 2 LAST CDS_LIB pure_quanta
J 0
(1325 2775);
DISPLAY INVISIBLE (1325 2775);
FORCEPROP 0 LAST CDS_LOCATION C1877
J 0
(1375 2925);
DISPLAY 1.021277 (1375 2925);
DISPLAY INVISIBLE (1375 2925);
FORCEPROP 0 LAST $SEC 1
J 0
(1375 2925);
DISPLAY 0.680851 (1375 2925);
PAINT MONO (1375 2925);
DISPLAY INVISIBLE (1375 2925);
FORCEPROP 0 LAST CDS_SEC 1
J 0
(1375 2925);
DISPLAY 1.021277 (1375 2925);
DISPLAY INVISIBLE (1375 2925);
FORCEADD UNIVERSAL_GND..1
(1325 2550);
FORCEPROP 3 LASTPIN (1325 2600) SIG_NAME GND\g
J 0
(1335 2610);
DISPLAY 0.659574 (1335 2610);
PAINT MONO (1335 2610);
DISPLAY INVISIBLE (1335 2610);
FORCEPROP 1 LAST HDL_POWER GND
J 1
(1350 2475);
DISPLAY 0.872340 (1350 2475);
PAINT GREEN (1350 2475);
DISPLAY INVISIBLE (1350 2475);
FORCEPROP 1 LAST PATH I35
J 0
(1400 2550);
DISPLAY 0.872340 (1400 2550);
PAINT AQUA (1400 2550);
DISPLAY INVISIBLE (1400 2550);
FORCEPROP 2 LAST CDS_LIB logical_power
J 0
(1325 2550);
DISPLAY INVISIBLE (1325 2550);
FORCEADD UNIVERSAL_GND..1
(1350 1700);
FORCEPROP 3 LASTPIN (1350 1750) SIG_NAME GND\g
J 0
(1360 1760);
DISPLAY 0.659574 (1360 1760);
PAINT MONO (1360 1760);
DISPLAY INVISIBLE (1360 1760);
FORCEPROP 2 LAST CDS_LIB logical_power
J 0
(1350 1700);
DISPLAY INVISIBLE (1350 1700);
FORCEPROP 1 LAST PATH I36
J 0
(1425 1700);
DISPLAY 0.872340 (1425 1700);
PAINT AQUA (1425 1700);
DISPLAY INVISIBLE (1425 1700);
FORCEPROP 1 LAST HDL_POWER GND
J 1
(1375 1625);
DISPLAY 0.872340 (1375 1625);
PAINT GREEN (1375 1625);
DISPLAY INVISIBLE (1375 1625);
FORCEADD Q_CAP..1
(1350 1925);
FORCEPROP 1 LAST PART_NUMBER CH4104K1B00
J 0
(1400 1775);
DISPLAY 0.510638 (1400 1775);
DISPLAY INVISIBLE (1400 1775);
FORCEPROP 1 LAST VOLTAGE 25V
J 0
(1400 1925);
DISPLAY 0.510638 (1400 1925);
FORCEPROP 1 LAST PACK_TYPE 0402
J 0
(1400 1725);
DISPLAY 0.510638 (1400 1725);
FORCEPROP 1 LAST MATERIAL X7R
J 0
(1400 1825);
DISPLAY 0.510638 (1400 1825);
FORCEPROP 1 LAST TOLERANCE 10%
J 0
(1400 1875);
DISPLAY 0.510638 (1400 1875);
FORCEPROP 1 LAST VALUE 0.1UF
J 0
(1400 1975);
DISPLAY 0.510638 (1400 1975);
FORCEPROP 1 LAST $LOCATION C1878
J 0
(1400 2025);
DISPLAY 0.638298 (1400 2025);
FORCEPROP 1 LASTPIN (1350 2025) $PN 1
J 0
(1360 2005);
DISPLAY 0.787234 (1360 2005);
PAINT MONO (1360 2005);
FORCEPROP 1 LASTPIN (1350 1825) $PN 2
J 0
(1360 1805);
DISPLAY 0.787234 (1360 1805);
PAINT MONO (1360 1805);
FORCEPROP 1 LAST PATH I37
J 0
(1400 2075);
DISPLAY 0.978723 (1400 2075);
PAINT WHITE (1400 2075);
DISPLAY INVISIBLE (1400 2075);
FORCEPROP 2 LAST CDS_LIB pure_quanta
J 0
(1350 1925);
DISPLAY INVISIBLE (1350 1925);
FORCEPROP 0 LAST CDS_LOCATION C1878
J 0
(1400 2075);
DISPLAY 1.021277 (1400 2075);
DISPLAY INVISIBLE (1400 2075);
FORCEPROP 0 LAST $SEC 1
J 0
(1400 2075);
DISPLAY 0.680851 (1400 2075);
PAINT MONO (1400 2075);
DISPLAY INVISIBLE (1400 2075);
FORCEPROP 0 LAST CDS_SEC 1
J 0
(1400 2075);
DISPLAY 1.021277 (1400 2075);
DISPLAY INVISIBLE (1400 2075);
FORCEADD UNIVERSAL_POWER..1
(1350 2175);
FORCEPROP 3 LASTPIN (1350 2125) SIG_NAME P3V3_AUX\g
J 0
(1360 2135);
DISPLAY 0.659574 (1360 2135);
PAINT MONO (1360 2135);
DISPLAY INVISIBLE (1360 2135);
FORCEPROP 1 LAST HDL_POWER P3V3_AUX
J 1
(1350 2225);
DISPLAY 0.872340 (1350 2225);
PAINT GREEN (1350 2225);
FORCEPROP 2 LAST CDS_LIB logical_power
J 0
(1350 2175);
DISPLAY INVISIBLE (1350 2175);
FORCEPROP 1 LAST PATH I38
J 0
(1400 2200);
DISPLAY 0.872340 (1400 2200);
PAINT AQUA (1400 2200);
DISPLAY INVISIBLE (1400 2200);
FORCEADD UNIVERSAL_GND..1
(-325 2625);
FORCEPROP 3 LASTPIN (-325 2675) SIG_NAME GND\g
J 0
(-315 2685);
DISPLAY 0.659574 (-315 2685);
PAINT MONO (-315 2685);
DISPLAY INVISIBLE (-315 2685);
FORCEPROP 2 LAST CDS_LIB logical_power
J 0
(-325 2625);
DISPLAY INVISIBLE (-325 2625);
FORCEPROP 1 LAST PATH I39
J 0
(-250 2625);
DISPLAY 0.872340 (-250 2625);
PAINT AQUA (-250 2625);
DISPLAY INVISIBLE (-250 2625);
FORCEPROP 1 LAST HDL_POWER GND
J 1
(-300 2550);
DISPLAY 0.872340 (-300 2550);
PAINT GREEN (-300 2550);
DISPLAY INVISIBLE (-300 2550);
FORCEADD OFFPAGE..1
(-2725 700);
FORCEPROP 2 LAST $XR1 162 
J 0
(-3127 700);
DISPLAY 0.638298 (-3127 700);
PAINT MONO (-3127 700);
FORCEPROP 2 LAST $XR0 159 
J 0
(-3007 700);
DISPLAY 0.638298 (-3007 700);
PAINT MONO (-3007 700);
FORCEPROP 2 LAST CDS_LIB standard
J 0
(-2725 700);
PAINT MONO (-2725 700);
DISPLAY INVISIBLE (-2725 700);
FORCEPROP 1 LAST OFFPAGE TRUE
J 0
(-2400 575);
DISPLAY 0.872340 (-2400 575);
PAINT GREEN (-2400 575);
DISPLAY INVISIBLE (-2400 575);
FORCEPROP 1 LAST COMMENT_BODY TRUE
J 0
(-2600 600);
DISPLAY 0.872340 (-2600 600);
PAINT GREEN (-2600 600);
DISPLAY INVISIBLE (-2600 600);
FORCEPROP 2 LAST PATH I4
J 0
(-3000 750);
DISPLAY 1.021277 (-3000 750);
DISPLAY INVISIBLE (-3000 750);
FORCEADD UNIVERSAL_POWER..1
(-325 3175);
FORCEPROP 3 LASTPIN (-325 3125) SIG_NAME P3V3_AUX\g
J 0
(-315 3135);
DISPLAY 0.659574 (-315 3135);
PAINT MONO (-315 3135);
DISPLAY INVISIBLE (-315 3135);
FORCEPROP 1 LAST HDL_POWER P3V3_AUX
J 1
(-325 3225);
DISPLAY 0.872340 (-325 3225);
PAINT GREEN (-325 3225);
FORCEPROP 2 LAST CDS_LIB logical_power
J 0
(-325 3175);
DISPLAY INVISIBLE (-325 3175);
FORCEPROP 1 LAST PATH I40
J 0
(-275 3200);
DISPLAY 0.872340 (-275 3200);
PAINT AQUA (-275 3200);
DISPLAY INVISIBLE (-275 3200);
FORCEADD Q_CAP..1
(-325 2850);
FORCEPROP 1 LAST PART_NUMBER CH4104K1B00
J 0
(-275 2700);
DISPLAY 0.510638 (-275 2700);
DISPLAY INVISIBLE (-275 2700);
FORCEPROP 1 LAST MATERIAL X7R
J 0
(-275 2750);
DISPLAY 0.510638 (-275 2750);
FORCEPROP 1 LAST VOLTAGE 25V
J 0
(-275 2850);
DISPLAY 0.510638 (-275 2850);
FORCEPROP 1 LAST TOLERANCE 10%
J 0
(-275 2800);
DISPLAY 0.510638 (-275 2800);
FORCEPROP 1 LAST PACK_TYPE 0402
J 0
(-275 2650);
DISPLAY 0.510638 (-275 2650);
FORCEPROP 1 LAST VALUE 0.1UF
J 0
(-275 2900);
DISPLAY 0.510638 (-275 2900);
FORCEPROP 1 LAST $LOCATION C1876
J 0
(-275 2950);
DISPLAY 0.978723 (-275 2950);
FORCEPROP 1 LASTPIN (-325 2950) $PN 1
J 0
(-315 2930);
DISPLAY 0.787234 (-315 2930);
PAINT MONO (-315 2930);
FORCEPROP 1 LASTPIN (-325 2750) $PN 2
J 0
(-315 2730);
DISPLAY 0.787234 (-315 2730);
PAINT MONO (-315 2730);
FORCEPROP 2 LAST CDS_LIB pure_quanta
J 0
(-325 2850);
DISPLAY INVISIBLE (-325 2850);
FORCEPROP 1 LAST PATH I41
J 0
(-275 3000);
DISPLAY 0.978723 (-275 3000);
PAINT WHITE (-275 3000);
DISPLAY INVISIBLE (-275 3000);
FORCEPROP 0 LAST CDS_LOCATION C1876
J 0
(-275 3000);
DISPLAY 1.021277 (-275 3000);
DISPLAY INVISIBLE (-275 3000);
FORCEPROP 0 LAST $SEC 1
J 0
(-275 3000);
DISPLAY 0.680851 (-275 3000);
PAINT MONO (-275 3000);
DISPLAY INVISIBLE (-275 3000);
FORCEPROP 0 LAST CDS_SEC 1
J 0
(-275 3000);
DISPLAY 1.021277 (-275 3000);
DISPLAY INVISIBLE (-275 3000);
FORCEADD UNIVERSAL_GND..1
(-400 2125);
FORCEPROP 3 LASTPIN (-400 2175) SIG_NAME GND\g
J 0
(-390 2185);
DISPLAY 0.659574 (-390 2185);
PAINT MONO (-390 2185);
DISPLAY INVISIBLE (-390 2185);
FORCEPROP 2 LAST CDS_LIB logical_power
J 0
(-400 2125);
DISPLAY INVISIBLE (-400 2125);
FORCEPROP 1 LAST PATH I42
J 0
(-325 2125);
DISPLAY 0.872340 (-325 2125);
PAINT AQUA (-325 2125);
DISPLAY INVISIBLE (-325 2125);
FORCEPROP 1 LAST HDL_POWER GND
J 1
(-375 2050);
DISPLAY 0.872340 (-375 2050);
PAINT GREEN (-375 2050);
DISPLAY INVISIBLE (-375 2050);
FORCEADD Q_RES..1
(825 2400);
FORCEPROP 1 LAST PART_NUMBER CS00002JB13
J 0
(775 2450);
DISPLAY 0.404255 (775 2450);
DISPLAY INVISIBLE (775 2450);
FORCEPROP 1 LAST VALUE 0
J 2
(975 2400);
DISPLAY 0.510638 (975 2400);
FORCEPROP 1 LAST TOLERANCE 5%
J 0
(1000 2400);
DISPLAY 0.510638 (1000 2400);
FORCEPROP 1 LAST WATTAGE 1/16W
J 2
(1000 2475);
DISPLAY 0.404255 (1000 2475);
FORCEPROP 1 LAST PACK_TYPE 0402LF
J 0
(775 2500);
DISPLAY 0.404255 (775 2500);
FORCEPROP 1 LAST MATERIAL CHIP
J 0
(775 2475);
DISPLAY 0.404255 (775 2475);
FORCEPROP 1 LAST $LOCATION R3303
J 0
(625 2400);
DISPLAY 0.638298 (625 2400);
FORCEPROP 1 LASTPIN (725 2400) $PN 1
J 0
(737 2412);
DISPLAY 0.787234 (737 2412);
PAINT MONO (737 2412);
FORCEPROP 1 LASTPIN (925 2400) $PN 2
J 0
(887 2412);
DISPLAY 0.787234 (887 2412);
PAINT MONO (887 2412);
FORCEPROP 2 LAST CDS_LIB pure_quanta
J 0
(825 2400);
DISPLAY INVISIBLE (825 2400);
FORCEPROP 1 LAST PATH I44
J 0
(775 2550);
DISPLAY 0.978723 (775 2550);
PAINT WHITE (775 2550);
DISPLAY INVISIBLE (775 2550);
FORCEPROP 0 LAST CDS_LOCATION R3303
J 0
(775 2525);
DISPLAY 1.021277 (775 2525);
DISPLAY INVISIBLE (775 2525);
FORCEPROP 0 LAST $SEC 1
J 0
(775 2525);
DISPLAY 0.680851 (775 2525);
PAINT MONO (775 2525);
DISPLAY INVISIBLE (775 2525);
FORCEPROP 0 LAST CDS_SEC 1
J 0
(775 2525);
DISPLAY 1.021277 (775 2525);
DISPLAY INVISIBLE (775 2525);
FORCEADD Q_RES..1
(625 1550);
FORCEPROP 1 LAST PART_NUMBER CS00002JB13
J 0
(575 1600);
DISPLAY 0.404255 (575 1600);
DISPLAY INVISIBLE (575 1600);
FORCEPROP 1 LAST VALUE 0
J 2
(775 1550);
DISPLAY 0.510638 (775 1550);
FORCEPROP 1 LAST TOLERANCE 5%
J 0
(800 1550);
DISPLAY 0.510638 (800 1550);
FORCEPROP 1 LAST WATTAGE 1/16W
J 2
(800 1625);
DISPLAY 0.404255 (800 1625);
FORCEPROP 1 LAST PACK_TYPE 0402LF
J 0
(575 1650);
DISPLAY 0.404255 (575 1650);
FORCEPROP 1 LAST MATERIAL CHIP
J 0
(575 1625);
DISPLAY 0.404255 (575 1625);
FORCEPROP 1 LAST $LOCATION R3304
J 0
(425 1550);
DISPLAY 0.638298 (425 1550);
FORCEPROP 1 LASTPIN (525 1550) $PN 1
J 0
(537 1562);
DISPLAY 0.787234 (537 1562);
PAINT MONO (537 1562);
FORCEPROP 1 LASTPIN (725 1550) $PN 2
J 0
(687 1562);
DISPLAY 0.787234 (687 1562);
PAINT MONO (687 1562);
FORCEPROP 1 LAST PATH I45
J 0
(575 1700);
DISPLAY 0.978723 (575 1700);
PAINT WHITE (575 1700);
DISPLAY INVISIBLE (575 1700);
FORCEPROP 2 LAST CDS_LIB pure_quanta
J 0
(625 1550);
DISPLAY INVISIBLE (625 1550);
FORCEPROP 0 LAST CDS_LOCATION R3304
J 0
(575 1675);
DISPLAY 1.021277 (575 1675);
DISPLAY INVISIBLE (575 1675);
FORCEPROP 0 LAST $SEC 1
J 0
(575 1675);
DISPLAY 0.680851 (575 1675);
PAINT MONO (575 1675);
DISPLAY INVISIBLE (575 1675);
FORCEPROP 0 LAST CDS_SEC 1
J 0
(575 1675);
DISPLAY 1.021277 (575 1675);
DISPLAY INVISIBLE (575 1675);
FORCEADD Q_RES..1
(825 275);
FORCEPROP 1 LAST PART_NUMBER CS00002JB13
J 0
(775 325);
DISPLAY 0.404255 (775 325);
DISPLAY INVISIBLE (775 325);
FORCEPROP 1 LAST VALUE 0
J 2
(975 275);
DISPLAY 0.510638 (975 275);
FORCEPROP 1 LAST WATTAGE 1/16W
J 2
(1000 350);
DISPLAY 0.404255 (1000 350);
FORCEPROP 1 LAST TOLERANCE 5%
J 0
(1000 275);
DISPLAY 0.510638 (1000 275);
FORCEPROP 1 LAST PACK_TYPE 0402LF
J 0
(775 375);
DISPLAY 0.404255 (775 375);
FORCEPROP 1 LAST MATERIAL CHIP
J 0
(775 350);
DISPLAY 0.404255 (775 350);
FORCEPROP 1 LAST $LOCATION R3308
J 0
(625 275);
DISPLAY 0.510638 (625 275);
FORCEPROP 1 LASTPIN (725 275) $PN 1
J 0
(737 287);
DISPLAY 0.787234 (737 287);
PAINT MONO (737 287);
FORCEPROP 1 LASTPIN (925 275) $PN 2
J 0
(887 287);
DISPLAY 0.787234 (887 287);
PAINT MONO (887 287);
FORCEPROP 1 LAST PATH I46
J 0
(775 425);
DISPLAY 0.978723 (775 425);
PAINT WHITE (775 425);
DISPLAY INVISIBLE (775 425);
FORCEPROP 2 LAST CDS_LIB pure_quanta
J 0
(825 275);
DISPLAY INVISIBLE (825 275);
FORCEPROP 0 LAST CDS_LOCATION R3308
J 0
(775 400);
DISPLAY 1.021277 (775 400);
DISPLAY INVISIBLE (775 400);
FORCEPROP 0 LAST $SEC 1
J 0
(775 400);
DISPLAY 0.680851 (775 400);
PAINT MONO (775 400);
DISPLAY INVISIBLE (775 400);
FORCEPROP 0 LAST CDS_SEC 1
J 0
(775 400);
DISPLAY 1.021277 (775 400);
DISPLAY INVISIBLE (775 400);
FORCEADD Q_RES..1
(800 -575);
FORCEPROP 1 LAST PART_NUMBER CS00002JB13
J 0
(750 -525);
DISPLAY 0.404255 (750 -525);
DISPLAY INVISIBLE (750 -525);
FORCEPROP 1 LAST WATTAGE 1/16W
J 2
(975 -500);
DISPLAY 0.404255 (975 -500);
FORCEPROP 1 LAST TOLERANCE 5%
J 0
(975 -575);
DISPLAY 0.510638 (975 -575);
FORCEPROP 1 LAST MATERIAL CHIP
J 0
(750 -500);
DISPLAY 0.404255 (750 -500);
FORCEPROP 1 LAST PACK_TYPE 0402LF
J 0
(750 -475);
DISPLAY 0.404255 (750 -475);
FORCEPROP 1 LAST VALUE 0
J 2
(950 -575);
DISPLAY 0.510638 (950 -575);
FORCEPROP 1 LAST $LOCATION R3306
J 0
(625 -575);
DISPLAY 0.510638 (625 -575);
FORCEPROP 1 LASTPIN (700 -575) $PN 1
J 0
(712 -563);
DISPLAY 0.787234 (712 -563);
PAINT MONO (712 -563);
FORCEPROP 1 LASTPIN (900 -575) $PN 2
J 0
(862 -563);
DISPLAY 0.787234 (862 -563);
PAINT MONO (862 -563);
FORCEPROP 1 LAST PATH I47
J 0
(750 -425);
DISPLAY 0.978723 (750 -425);
PAINT WHITE (750 -425);
DISPLAY INVISIBLE (750 -425);
FORCEPROP 2 LAST CDS_LIB pure_quanta
J 0
(800 -575);
DISPLAY INVISIBLE (800 -575);
FORCEPROP 0 LAST CDS_LOCATION R3306
J 0
(750 -450);
DISPLAY 1.021277 (750 -450);
DISPLAY INVISIBLE (750 -450);
FORCEPROP 0 LAST $SEC 1
J 0
(750 -450);
DISPLAY 0.680851 (750 -450);
PAINT MONO (750 -450);
DISPLAY INVISIBLE (750 -450);
FORCEPROP 0 LAST CDS_SEC 1
J 0
(750 -450);
DISPLAY 1.021277 (750 -450);
DISPLAY INVISIBLE (750 -450);
FORCEADD OFFPAGE..1
R 2
(3100 1450);
FORCEPROP 2 LAST $XR0 154 
J 0
(3286 1450);
DISPLAY 0.638298 (3286 1450);
PAINT MONO (3286 1450);
FORCEPROP 1 LAST COMMENT_BODY TRUE
J 2
(2975 1350);
DISPLAY 0.872340 (2975 1350);
PAINT GREEN (2975 1350);
DISPLAY INVISIBLE (2975 1350);
FORCEPROP 1 LAST OFFPAGE TRUE
J 2
(2775 1325);
DISPLAY 0.872340 (2775 1325);
PAINT GREEN (2775 1325);
DISPLAY INVISIBLE (2775 1325);
FORCEPROP 2 LAST PATH I48
J 0
(3275 1525);
DISPLAY 1.021277 (3275 1525);
DISPLAY INVISIBLE (3275 1525);
FORCEPROP 2 LAST CDS_LIB standard
J 2
(3100 1450);
DISPLAY INVISIBLE (3100 1450);
FORCEADD OFFPAGE..2
R 2
(-350 1450);
FORCEPROP 2 LAST $XR0 165 
J 0
(-605 1450);
DISPLAY 0.638298 (-605 1450);
PAINT MONO (-605 1450);
FORCEPROP 2 LAST CDS_LIB standard
J 2
(-350 1450);
DISPLAY INVISIBLE (-350 1450);
FORCEPROP 2 LAST PATH I49
J 2
(-525 1525);
DISPLAY 1.021277 (-525 1525);
DISPLAY INVISIBLE (-525 1525);
FORCEPROP 1 LAST COMMENT_BODY TRUE
J 2
(-305 1355);
DISPLAY 0.872340 (-305 1355);
PAINT GREEN (-305 1355);
DISPLAY INVISIBLE (-305 1355);
FORCEPROP 1 LAST OFFPAGE TRUE
J 2
(-675 1325);
DISPLAY 0.872340 (-675 1325);
PAINT GREEN (-675 1325);
DISPLAY INVISIBLE (-675 1325);
FORCEADD OFFPAGE..1
(-2725 -200);
FORCEPROP 2 LAST $XR1 162 
J 0
(-3127 -200);
DISPLAY 0.638298 (-3127 -200);
PAINT MONO (-3127 -200);
FORCEPROP 2 LAST $XR0 159 
J 0
(-3007 -200);
DISPLAY 0.638298 (-3007 -200);
PAINT MONO (-3007 -200);
FORCEPROP 1 LAST COMMENT_BODY TRUE
J 0
(-2600 -300);
DISPLAY 0.872340 (-2600 -300);
PAINT GREEN (-2600 -300);
DISPLAY INVISIBLE (-2600 -300);
FORCEPROP 1 LAST OFFPAGE TRUE
J 0
(-2400 -325);
DISPLAY 0.872340 (-2400 -325);
PAINT GREEN (-2400 -325);
DISPLAY INVISIBLE (-2400 -325);
FORCEPROP 2 LAST CDS_LIB standard
J 0
(-2725 -200);
PAINT MONO (-2725 -200);
DISPLAY INVISIBLE (-2725 -200);
FORCEPROP 2 LAST PATH I5
J 0
(-3000 -150);
DISPLAY 1.021277 (-3000 -150);
DISPLAY INVISIBLE (-3000 -150);
FORCEADD Q_RES..1
(625 1450);
FORCEPROP 1 LAST PART_NUMBER CS00002JB13
J 0
(525 1375);
DISPLAY 0.404255 (525 1375);
DISPLAY INVISIBLE (525 1375);
FORCEPROP 1 LAST PACK_TYPE 0402LF
J 0
(525 1400);
DISPLAY 0.404255 (525 1400);
FORCEPROP 1 LAST WATTAGE 1/16W
J 2
(750 1400);
DISPLAY 0.404255 (750 1400);
FORCEPROP 1 LAST TOLERANCE 5%
J 0
(800 1450);
DISPLAY 0.510638 (800 1450);
FORCEPROP 1 LAST VALUE 0
J 2
(775 1450);
DISPLAY 0.510638 (775 1450);
FORCEPROP 1 LAST MATERIAL CHIP
J 0
(525 1350);
DISPLAY 0.404255 (525 1350);
FORCEPROP 1 LAST $LOCATION R3305
J 0
(425 1450);
DISPLAY 0.638298 (425 1450);
FORCEPROP 1 LASTPIN (525 1450) $PN 1
J 0
(537 1462);
DISPLAY 0.787234 (537 1462);
PAINT MONO (537 1462);
FORCEPROP 1 LASTPIN (725 1450) $PN 2
J 0
(687 1462);
DISPLAY 0.787234 (687 1462);
PAINT MONO (687 1462);
FORCEPROP 1 LAST PATH I50
J 0
(575 1600);
DISPLAY 0.978723 (575 1600);
PAINT WHITE (575 1600);
DISPLAY INVISIBLE (575 1600);
FORCEPROP 2 LAST CDS_LIB pure_quanta
J 0
(625 1450);
DISPLAY INVISIBLE (625 1450);
FORCEPROP 0 LAST CDS_LOCATION R3305
J 0
(575 1525);
DISPLAY 1.021277 (575 1525);
DISPLAY INVISIBLE (575 1525);
FORCEPROP 0 LAST $SEC 1
J 0
(575 1525);
DISPLAY 0.680851 (575 1525);
PAINT MONO (575 1525);
DISPLAY INVISIBLE (575 1525);
FORCEPROP 0 LAST CDS_SEC 1
J 0
(575 1525);
DISPLAY 1.021277 (575 1525);
DISPLAY INVISIBLE (575 1525);
FORCEADD OFFPAGE..1
(1225 175);
FORCEPROP 2 LAST $XR0 165 
J 0
(943 175);
DISPLAY 0.638298 (943 175);
PAINT MONO (943 175);
FORCEPROP 2 LAST PATH I51
J 2
(1050 250);
DISPLAY 1.021277 (1050 250);
DISPLAY INVISIBLE (1050 250);
FORCEPROP 1 LAST OFFPAGE TRUE
J 0
(1550 50);
DISPLAY 0.872340 (1550 50);
PAINT GREEN (1550 50);
DISPLAY INVISIBLE (1550 50);
FORCEPROP 1 LAST COMMENT_BODY TRUE
J 0
(1350 75);
DISPLAY 0.872340 (1350 75);
PAINT GREEN (1350 75);
DISPLAY INVISIBLE (1350 75);
FORCEPROP 2 LAST CDS_LIB standard
J 2
(1225 175);
DISPLAY INVISIBLE (1225 175);
FORCEADD Q_RES..1
(800 -675);
FORCEPROP 1 LAST PART_NUMBER CS00002JB13
J 0
(750 -750);
DISPLAY 0.404255 (750 -750);
DISPLAY INVISIBLE (750 -750);
FORCEPROP 1 LAST PACK_TYPE 0402LF
J 0
(750 -725);
DISPLAY 0.404255 (750 -725);
FORCEPROP 1 LAST TOLERANCE 5%
J 0
(975 -675);
DISPLAY 0.510638 (975 -675);
FORCEPROP 1 LAST MATERIAL CHIP
J 0
(750 -775);
DISPLAY 0.404255 (750 -775);
FORCEPROP 1 LAST VALUE 0
J 2
(950 -675);
DISPLAY 0.510638 (950 -675);
FORCEPROP 1 LAST WATTAGE 1/16W
J 2
(950 -725);
DISPLAY 0.404255 (950 -725);
FORCEPROP 1 LAST $LOCATION R3307
J 0
(625 -675);
DISPLAY 0.510638 (625 -675);
FORCEPROP 1 LASTPIN (700 -675) $PN 1
J 0
(712 -663);
DISPLAY 0.787234 (712 -663);
PAINT MONO (712 -663);
FORCEPROP 1 LASTPIN (900 -675) $PN 2
J 0
(862 -663);
DISPLAY 0.787234 (862 -663);
PAINT MONO (862 -663);
FORCEPROP 1 LAST PATH I52
J 0
(750 -525);
DISPLAY 0.978723 (750 -525);
PAINT WHITE (750 -525);
DISPLAY INVISIBLE (750 -525);
FORCEPROP 2 LAST CDS_LIB pure_quanta
J 0
(800 -675);
DISPLAY INVISIBLE (800 -675);
FORCEPROP 0 LAST CDS_LOCATION R3307
J 0
(750 -600);
DISPLAY 1.021277 (750 -600);
DISPLAY INVISIBLE (750 -600);
FORCEPROP 0 LAST $SEC 1
J 0
(750 -600);
DISPLAY 0.680851 (750 -600);
PAINT MONO (750 -600);
DISPLAY INVISIBLE (750 -600);
FORCEPROP 0 LAST CDS_SEC 1
J 0
(750 -600);
DISPLAY 1.021277 (750 -600);
DISPLAY INVISIBLE (750 -600);
FORCEADD OFFPAGE..2
R 2
(-200 -675);
FORCEPROP 2 LAST $XR0 165 
J 0
(-455 -675);
DISPLAY 0.638298 (-455 -675);
PAINT MONO (-455 -675);
FORCEPROP 2 LAST PATH I53
J 0
(-150 -600);
DISPLAY 1.021277 (-150 -600);
DISPLAY INVISIBLE (-150 -600);
FORCEPROP 2 LAST CDS_LIB standard
J 2
(-200 -675);
DISPLAY INVISIBLE (-200 -675);
FORCEPROP 1 LAST COMMENT_BODY TRUE
J 2
(-155 -770);
DISPLAY 0.872340 (-155 -770);
PAINT GREEN (-155 -770);
DISPLAY INVISIBLE (-155 -770);
FORCEPROP 1 LAST OFFPAGE TRUE
J 2
(-525 -800);
DISPLAY 0.872340 (-525 -800);
PAINT GREEN (-525 -800);
DISPLAY INVISIBLE (-525 -800);
FORCEADD OFFPAGE..1
(700 2300);
FORCEPROP 2 LAST $XR0 165 
J 0
(448 2300);
DISPLAY 0.638298 (448 2300);
PAINT MONO (448 2300);
FORCEPROP 1 LAST COMMENT_BODY TRUE
J 0
(825 2200);
DISPLAY 0.872340 (825 2200);
PAINT GREEN (825 2200);
DISPLAY INVISIBLE (825 2200);
FORCEPROP 1 LAST OFFPAGE TRUE
J 0
(1025 2175);
DISPLAY 0.872340 (1025 2175);
PAINT GREEN (1025 2175);
DISPLAY INVISIBLE (1025 2175);
FORCEPROP 2 LAST PATH I54
J 0
(750 2375);
DISPLAY 1.021277 (750 2375);
DISPLAY INVISIBLE (750 2375);
FORCEPROP 2 LAST CDS_LIB standard
J 0
(700 2300);
DISPLAY INVISIBLE (700 2300);
FORCEADD OFFPAGE..2
(3100 2300);
FORCEPROP 2 LAST $XR0 154 
J 0
(3289 2300);
DISPLAY 0.638298 (3289 2300);
PAINT MONO (3289 2300);
FORCEPROP 1 LAST OFFPAGE TRUE
J 0
(3425 2175);
DISPLAY 0.872340 (3425 2175);
PAINT GREEN (3425 2175);
DISPLAY INVISIBLE (3425 2175);
FORCEPROP 1 LAST COMMENT_BODY TRUE
J 0
(3055 2205);
DISPLAY 0.872340 (3055 2205);
PAINT GREEN (3055 2205);
DISPLAY INVISIBLE (3055 2205);
FORCEPROP 2 LAST PATH I56
J 2
(3050 2375);
DISPLAY 1.021277 (3050 2375);
DISPLAY INVISIBLE (3050 2375);
FORCEPROP 2 LAST CDS_LIB standard
J 2
(3100 2300);
DISPLAY INVISIBLE (3100 2300);
FORCEADD OFFPAGE..2
(3350 175);
FORCEPROP 2 LAST $XR0 160 
J 0
(3539 175);
DISPLAY 0.638298 (3539 175);
PAINT MONO (3539 175);
FORCEPROP 1 LAST COMMENT_BODY TRUE
J 0
(3305 80);
DISPLAY 0.872340 (3305 80);
PAINT GREEN (3305 80);
DISPLAY INVISIBLE (3305 80);
FORCEPROP 1 LAST OFFPAGE TRUE
J 0
(3675 50);
DISPLAY 0.872340 (3675 50);
PAINT GREEN (3675 50);
DISPLAY INVISIBLE (3675 50);
FORCEPROP 2 LAST PATH I58
J 0
(3525 250);
DISPLAY 1.021277 (3525 250);
DISPLAY INVISIBLE (3525 250);
FORCEPROP 2 LAST CDS_LIB standard
J 0
(3350 175);
DISPLAY INVISIBLE (3350 175);
FORCEADD OFFPAGE..1
R 2
(3375 -675);
FORCEPROP 2 LAST $XR0 160 
J 0
(3561 -675);
DISPLAY 0.638298 (3561 -675);
PAINT MONO (3561 -675);
FORCEPROP 2 LAST PATH I59
J 0
(3550 -600);
DISPLAY 1.021277 (3550 -600);
DISPLAY INVISIBLE (3550 -600);
FORCEPROP 1 LAST OFFPAGE TRUE
J 2
(3050 -800);
DISPLAY 0.872340 (3050 -800);
PAINT GREEN (3050 -800);
DISPLAY INVISIBLE (3050 -800);
FORCEPROP 1 LAST COMMENT_BODY TRUE
J 2
(3250 -775);
DISPLAY 0.872340 (3250 -775);
PAINT GREEN (3250 -775);
DISPLAY INVISIBLE (3250 -775);
FORCEPROP 2 LAST CDS_LIB standard
J 0
(3375 -675);
DISPLAY INVISIBLE (3375 -675);
FORCEADD OFFPAGE..1
(-2725 -100);
FORCEPROP 2 LAST $XR1 162 
J 0
(-3127 -100);
DISPLAY 0.638298 (-3127 -100);
PAINT MONO (-3127 -100);
FORCEPROP 2 LAST $XR0 159 
J 0
(-3007 -100);
DISPLAY 0.638298 (-3007 -100);
PAINT MONO (-3007 -100);
FORCEPROP 1 LAST COMMENT_BODY TRUE
J 0
(-2600 -200);
DISPLAY 0.872340 (-2600 -200);
PAINT GREEN (-2600 -200);
DISPLAY INVISIBLE (-2600 -200);
FORCEPROP 1 LAST OFFPAGE TRUE
J 0
(-2400 -225);
DISPLAY 0.872340 (-2400 -225);
PAINT GREEN (-2400 -225);
DISPLAY INVISIBLE (-2400 -225);
FORCEPROP 2 LAST CDS_LIB standard
J 0
(-2725 -100);
PAINT MONO (-2725 -100);
DISPLAY INVISIBLE (-2725 -100);
FORCEPROP 2 LAST PATH I6
J 0
(-3000 -50);
DISPLAY 1.021277 (-3000 -50);
DISPLAY INVISIBLE (-3000 -50);
FORCEADD UNIVERSAL_GND..1
(2375 2175);
FORCEPROP 3 LASTPIN (2375 2225) SIG_NAME GND\g
J 0
(2385 2235);
DISPLAY 0.659574 (2385 2235);
PAINT MONO (2385 2235);
DISPLAY INVISIBLE (2385 2235);
FORCEPROP 2 LAST CDS_LIB logical_power
J 0
(2375 2175);
DISPLAY INVISIBLE (2375 2175);
FORCEPROP 1 LAST PATH I60
J 0
(2450 2175);
DISPLAY 0.872340 (2450 2175);
PAINT AQUA (2450 2175);
DISPLAY INVISIBLE (2450 2175);
FORCEPROP 1 LAST HDL_POWER GND
J 1
(2400 2100);
DISPLAY 0.872340 (2400 2100);
PAINT GREEN (2400 2100);
DISPLAY INVISIBLE (2400 2100);
FORCEADD UNIVERSAL_GND..1
(2375 1325);
FORCEPROP 3 LASTPIN (2375 1375) SIG_NAME GND\g
J 0
(2385 1385);
DISPLAY 0.659574 (2385 1385);
PAINT MONO (2385 1385);
DISPLAY INVISIBLE (2385 1385);
FORCEPROP 1 LAST HDL_POWER GND
J 1
(2400 1250);
DISPLAY 0.872340 (2400 1250);
PAINT GREEN (2400 1250);
DISPLAY INVISIBLE (2400 1250);
FORCEPROP 1 LAST PATH I61
J 0
(2450 1325);
DISPLAY 0.872340 (2450 1325);
PAINT AQUA (2450 1325);
DISPLAY INVISIBLE (2450 1325);
FORCEPROP 2 LAST CDS_LIB logical_power
J 0
(2375 1325);
DISPLAY INVISIBLE (2375 1325);
FORCEADD UNIVERSAL_GND..1
(2550 50);
FORCEPROP 3 LASTPIN (2550 100) SIG_NAME GND\g
J 0
(2560 110);
DISPLAY 0.659574 (2560 110);
PAINT MONO (2560 110);
DISPLAY INVISIBLE (2560 110);
FORCEPROP 1 LAST HDL_POWER GND
J 1
(2575 -25);
DISPLAY 0.872340 (2575 -25);
PAINT GREEN (2575 -25);
DISPLAY INVISIBLE (2575 -25);
FORCEPROP 1 LAST PATH I62
J 0
(2625 50);
DISPLAY 0.872340 (2625 50);
PAINT AQUA (2625 50);
DISPLAY INVISIBLE (2625 50);
FORCEPROP 2 LAST CDS_LIB logical_power
J 0
(2550 50);
DISPLAY INVISIBLE (2550 50);
FORCEADD UNIVERSAL_GND..1
(2525 -800);
FORCEPROP 3 LASTPIN (2525 -750) SIG_NAME GND\g
J 0
(2535 -740);
DISPLAY 0.659574 (2535 -740);
PAINT MONO (2535 -740);
DISPLAY INVISIBLE (2535 -740);
FORCEPROP 1 LAST HDL_POWER GND
J 1
(2550 -875);
DISPLAY 0.872340 (2550 -875);
PAINT GREEN (2550 -875);
DISPLAY INVISIBLE (2550 -875);
FORCEPROP 1 LAST PATH I63
J 0
(2600 -800);
DISPLAY 0.872340 (2600 -800);
PAINT AQUA (2600 -800);
DISPLAY INVISIBLE (2600 -800);
FORCEPROP 2 LAST CDS_LIB logical_power
J 0
(2525 -800);
DISPLAY INVISIBLE (2525 -800);
FORCEADD OFFPAGE..1
(-2750 2900);
FORCEPROP 2 LAST $XR1 156 
J 0
(-3122 2900);
DISPLAY 0.638298 (-3122 2900);
PAINT MONO (-3122 2900);
FORCEPROP 2 LAST $XR0 153 
J 0
(-3002 2900);
DISPLAY 0.638298 (-3002 2900);
PAINT MONO (-3002 2900);
FORCEPROP 2 LAST PATH I7
J 0
(-3000 2950);
DISPLAY 1.021277 (-3000 2950);
DISPLAY INVISIBLE (-3000 2950);
FORCEPROP 2 LAST CDS_LIB standard
J 0
(-2750 2900);
PAINT MONO (-2750 2900);
DISPLAY INVISIBLE (-2750 2900);
FORCEPROP 1 LAST OFFPAGE TRUE
J 0
(-2425 2775);
DISPLAY 0.872340 (-2425 2775);
PAINT GREEN (-2425 2775);
DISPLAY INVISIBLE (-2425 2775);
FORCEPROP 1 LAST COMMENT_BODY TRUE
J 0
(-2625 2800);
DISPLAY 0.872340 (-2625 2800);
PAINT GREEN (-2625 2800);
DISPLAY INVISIBLE (-2625 2800);
FORCEADD OFFPAGE..1
(-2750 2000);
FORCEPROP 2 LAST $XR1 156 
J 0
(-3122 2000);
DISPLAY 0.638298 (-3122 2000);
PAINT MONO (-3122 2000);
FORCEPROP 2 LAST $XR0 153 
J 0
(-3002 2000);
DISPLAY 0.638298 (-3002 2000);
PAINT MONO (-3002 2000);
FORCEPROP 2 LAST PATH I8
J 0
(-3000 2050);
DISPLAY 1.021277 (-3000 2050);
DISPLAY INVISIBLE (-3000 2050);
FORCEPROP 1 LAST COMMENT_BODY TRUE
J 0
(-2625 1900);
DISPLAY 0.872340 (-2625 1900);
PAINT GREEN (-2625 1900);
DISPLAY INVISIBLE (-2625 1900);
FORCEPROP 1 LAST OFFPAGE TRUE
J 0
(-2425 1875);
DISPLAY 0.872340 (-2425 1875);
PAINT GREEN (-2425 1875);
DISPLAY INVISIBLE (-2425 1875);
FORCEPROP 2 LAST CDS_LIB standard
J 0
(-2750 2000);
PAINT MONO (-2750 2000);
DISPLAY INVISIBLE (-2750 2000);
FORCEADD OFFPAGE..1
(-2750 1900);
FORCEPROP 2 LAST $XR1 156 
J 0
(-3122 1900);
DISPLAY 0.638298 (-3122 1900);
PAINT MONO (-3122 1900);
FORCEPROP 2 LAST $XR0 153 
J 0
(-3002 1900);
DISPLAY 0.638298 (-3002 1900);
PAINT MONO (-3002 1900);
FORCEPROP 2 LAST PATH I9
J 0
(-3000 1950);
DISPLAY 1.021277 (-3000 1950);
DISPLAY INVISIBLE (-3000 1950);
FORCEPROP 1 LAST COMMENT_BODY TRUE
J 0
(-2625 1800);
DISPLAY 0.872340 (-2625 1800);
PAINT GREEN (-2625 1800);
DISPLAY INVISIBLE (-2625 1800);
FORCEPROP 1 LAST OFFPAGE TRUE
J 0
(-2425 1775);
DISPLAY 0.872340 (-2425 1775);
PAINT GREEN (-2425 1775);
DISPLAY INVISIBLE (-2425 1775);
FORCEPROP 2 LAST CDS_LIB standard
J 0
(-2750 1900);
PAINT MONO (-2750 1900);
DISPLAY INVISIBLE (-2750 1900);
FORCEADD DNS..2
(2200 -675);
PAINT RED (2200 -675);
FORCEPROP 1 LAST COMMENT_BODY TRUE
R 1
J 0
(2275 -900);
DISPLAY 0.872340 (2275 -900);
PAINT GREEN (2275 -900);
DISPLAY INVISIBLE (2275 -900);
FORCEPROP 2 LAST CDS_LIB mstr_misc
J 0
(2200 -675);
DISPLAY INVISIBLE (2200 -675);
FORCEADD DNS..2
(2200 200);
PAINT RED (2200 200);
FORCEPROP 1 LAST COMMENT_BODY TRUE
R 1
J 0
(2275 -25);
DISPLAY 0.872340 (2275 -25);
PAINT GREEN (2275 -25);
DISPLAY INVISIBLE (2275 -25);
FORCEPROP 2 LAST CDS_LIB mstr_misc
J 0
(2200 200);
DISPLAY INVISIBLE (2200 200);
FORCEADD DNS..2
(2000 1425);
PAINT RED (2000 1425);
FORCEPROP 1 LAST COMMENT_BODY TRUE
R 1
J 0
(2075 1200);
DISPLAY 0.872340 (2075 1200);
PAINT GREEN (2075 1200);
DISPLAY INVISIBLE (2075 1200);
FORCEPROP 2 LAST CDS_LIB mstr_misc
J 0
(2000 1425);
DISPLAY INVISIBLE (2000 1425);
FORCEADD DNS..2
(2025 2300);
PAINT RED (2025 2300);
FORCEPROP 1 LAST COMMENT_BODY TRUE
R 1
J 0
(2100 2075);
DISPLAY 0.872340 (2100 2075);
PAINT GREEN (2100 2075);
DISPLAY INVISIBLE (2100 2075);
FORCEPROP 2 LAST CDS_LIB mstr_misc
J 0
(2025 2300);
DISPLAY INVISIBLE (2025 2300);
FORCEADD QUANTA_TITLE_BLOCK_C..1
(5100 -2650);
FORCEPROP 0 LAST CDS_CON_LAST_MODIFIED Fri Aug 25 14:02:36 2023
J 0
(3215 -2635);
DISPLAY INVISIBLE (3215 -2635);
FORCEPROP 1 LAST CUSTOM_TXT_CDS <CON_LAST_MODIFIED>
J 0
(3215 -2635);
DISPLAY 0.978723 (3215 -2635);
FORCEPROP 2 LAST CUSTOM_TXT_CDS <XR_PAGE_TITLE>
J 0
(-2790 2600);
DISPLAY 0.638298 (-2790 2600);
PAINT PINK (-2790 2600);
DISPLAY INVISIBLE (-2790 2600);
FORCEPROP 1 LAST CUSTOM_TXT_CDS <NAME_2>
J 0
(1925 -2600);
FORCEPROP 1 LAST CUSTOM_TXT_CDS <NAME_1>
J 0
(1925 -2475);
FORCEPROP 1 LAST CUSTOM_TXT_CDS <Q_NUMBER>
J 0
(3697 -2547);
DISPLAY 1.212766 (3697 -2547);
FORCEPROP 1 LAST CUSTOM_TXT_CDS <Q_PROJ>
J 0
(2718 -2548);
DISPLAY 1.212766 (2718 -2548);
FORCEPROP 1 LAST CUSTOM_TXT_CDS <Q_REV>
J 0
(4916 -2547);
DISPLAY 1.212766 (4916 -2547);
FORCEPROP 1 LAST CUSTOM_TXT_CDS <CON_PAGE_NUM> OF <CON_TOTAL_PAGES>
J 0
(4654 -2632);
DISPLAY 0.978723 (4654 -2632);
FORCEPROP 1 LAST Q_TITLE OCP3.0 NCSI
J 0
(-4266 -2624);
DISPLAY 2.446809 (-4266 -2624);
PAINT GREEN (-4266 -2624);
FORCEPROP 1 LAST Q_DEPT 
J 1
(1337 -2601);
DISPLAY 1.957447 (1337 -2601);
PAINT GREEN (1337 -2601);
FORCEPROP 2 LAST CDS_XR_PAGE_TITLE CR-165 : @S9S_MB_2U_LIB.S9S_MB_2U(SCH_1):PAGE165
J 0
(-2790 2600);
DISPLAY 0.638298 (-2790 2600);
PAINT PINK (-2790 2600);
DISPLAY INVISIBLE (-2790 2600);
FORCEPROP 2 LAST CDS_LIB pure_quanta
J 0
(5100 -2650);
DISPLAY INVISIBLE (5100 -2650);
FORCEPROP 1 LAST CDS_LMAN_SYM_OUTLINE -9475,6775,100,-125
J 0
(5100 -2650);
DISPLAY 0.468085 (5100 -2650);
PAINT GREEN (5100 -2650);
DISPLAY INVISIBLE (5100 -2650);
FORCEPROP 1 LAST COMMENT_BODY TRUE
J 0
(5112 -2663);
DISPLAY 0.978723 (5112 -2663);
PAINT GREEN (5112 -2663);
DISPLAY INVISIBLE (5112 -2663);
FORCEPROP 2 LAST PAGE_BORDER TRUE
J 0
(-2790 2600);
DISPLAY 0.638298 (-2790 2600);
PAINT PINK (-2790 2600);
DISPLAY INVISIBLE (-2790 2600);
WIRE 16 -1 (-325 3125)(-325 3025);
WIRE 16 -1 (-1500 1450)(-1500 1350);
WIRE 16 -1 (-1600 3525)(-1600 3450);
WIRE 16 -1 (1525 -25)(1525 -50);
WIRE 16 -1 (1525 775)(1525 850);
WIRE 16 -1 (1850 775)(1525 775);
WIRE 16 -1 (1525 675)(1525 775);
WIRE 16 -1 (1350 2100)(1350 2125);
WIRE 16 -1 (1675 2100)(1350 2100);
WIRE 16 -1 (1350 2025)(1350 2100);
WIRE 16 -1 (1325 2975)(1325 3050);
WIRE 16 -1 (1675 2975)(1325 2975);
WIRE 16 -1 (1325 2875)(1325 2975);
WIRE 16 -1 (-1725 600)(-1725 525);
WIRE 16 -1 (-1725 2700)(-1725 2625);
WIRE 16 -1 (-1500 1075)(-1500 1000);
WIRE 16 -1 (-1600 3150)(-1600 3075);
WIRE 16 -1 (-400 2250)(-400 2175);
WIRE 16 -1 (-325 2750)(-325 2675);
WIRE 16 -1 (1325 2675)(1325 2600);
WIRE 16 -1 (1525 -350)(1525 -425);
WIRE 16 -1 (1525 475)(1525 400);
WIRE 16 -1 (2525 -625)(2525 -750);
WIRE 16 -1 (2475 -625)(2525 -625);
WIRE 16 -1 (2550 225)(2550 100);
WIRE 16 -1 (2500 225)(2550 225);
WIRE 16 -1 (1350 1825)(1350 1750);
WIRE 16 -1 (2375 1500)(2375 1375);
WIRE 16 -1 (2325 1500)(2375 1500);
WIRE 16 -1 (2375 2350)(2375 2225);
WIRE 16 -1 (2325 2350)(2375 2350);
WIRE 16 -1 (3650 -575)(2475 -575);
WIRE 16 -1 (3650 275)(3650 -575);
WIRE 16 -1 (2500 275)(3650 275);
FORCEPROP 2 LAST SIG_NAME OCP_V3_2_NOT_PRSNT_RBT_ARB_IN
J 0
(2615 285);
DISPLAY 0.638298 (2615 285);
PAINT WHITE (2615 285);
WIRE 16 -1 (925 275)(1900 275);
FORCEPROP 2 LAST SIG_NAME OCP_V3_2_PRSNT_ALL_R1_N
J 0
(1290 285);
DISPLAY 0.510638 (1290 285);
PAINT WHITE (1290 285);
WIRE 16 -1 (1850 225)(1850 775);
WIRE 16 -1 (1900 225)(1850 225);
WIRE 16 -1 (1675 1500)(1675 2100);
WIRE 16 -1 (1725 1500)(1675 1500);
WIRE 16 -1 (-1725 900)(-1725 1350);
WIRE 16 -1 (-1500 1350)(-1725 1350);
WIRE 16 -1 (-1500 1350)(-1500 1275);
WIRE 16 -1 (525 1450)(-300 1450);
FORCEPROP 2 LAST SIG_NAME OCP_SFF_RBT_ARB_IN_MUX1
J 0
(-260 1460);
DISPLAY 0.553191 (-260 1460);
PAINT WHITE (-260 1460);
WIRE 16 -1 (725 1550)(1725 1550);
FORCEPROP 2 LAST SIG_NAME OCP_SFF_PRSNT_ALL_R3_N
J 0
(1015 1560);
DISPLAY 0.510638 (1015 1560);
PAINT WHITE (1015 1560);
WIRE 16 -1 (3425 1550)(2325 1550);
WIRE 16 -1 (3425 2400)(3425 1550);
WIRE 16 -1 (2325 2400)(3425 2400);
FORCEPROP 2 LAST SIG_NAME OCP_SFF_NOT_PRSNT_RBT_ARB_IN
J 0
(2440 2410);
DISPLAY 0.638298 (2440 2410);
PAINT WHITE (2440 2410);
WIRE 16 -1 (2325 1450)(3050 1450);
FORCEPROP 2 LAST SIG_NAME OCP_SFF_RBT_ARB_IN
J 0
(2440 1460);
DISPLAY 0.553191 (2440 1460);
PAINT WHITE (2440 1460);
WIRE 16 -1 (2325 2300)(3050 2300);
FORCEPROP 2 LAST SIG_NAME OCP_SFF_RBT_ARB_OUT
J 0
(2440 2310);
DISPLAY 0.553191 (2440 2310);
PAINT WHITE (2440 2310);
WIRE 16 -1 (1725 1450)(725 1450);
FORCEPROP 2 LAST SIG_NAME OCP_SFF_RBT_ARB_IN_MUX1_R
J 0
(1015 1460);
DISPLAY 0.553191 (1015 1460);
PAINT WHITE (1015 1460);
WIRE 16 -1 (175 1550)(525 1550);
WIRE 16 -1 (-100 2400)(175 2400);
FORCEPROP 2 LAST SIG_NAME OCP_SFF_PRSNT_ALL_R_N
J 0
(40 2410);
DISPLAY 0.553191 (40 2410);
PAINT WHITE (40 2410);
WIRE 16 -1 (175 2400)(175 1550);
WIRE 16 -1 (175 2400)(725 2400);
FORCEPROP 0 LAST CDS_PHYS_NET_NAME OCP_SFF_PRSNT0_R_N
J 0
(215 2442);
PAINT MONO (215 2442);
DISPLAY INVISIBLE (215 2442);
WIRE 16 -1 (-1425 1950)(-850 1950);
FORCEPROP 0 LAST CDS_PHYS_NET_NAME OCP_SFF_PRSNT0_R_N
J 0
(-935 1992);
PAINT MONO (-935 1992);
DISPLAY INVISIBLE (-935 1992);
FORCEPROP 2 LAST SIG_NAME OCP_SFF_PRSNT23_R_N
J 0
(-1385 1960);
DISPLAY 0.553191 (-1385 1960);
PAINT WHITE (-1385 1960);
WIRE 16 -1 (-850 1950)(-850 2350);
WIRE 16 -1 (-850 2350)(-700 2350);
WIRE 16 -1 (-850 2450)(-700 2450);
WIRE 16 -1 (-1425 2850)(-850 2850);
FORCEPROP 0 LAST CDS_PHYS_NET_NAME OCP_SFF_PRSNT0_R_N
J 0
(-935 2892);
PAINT MONO (-935 2892);
DISPLAY INVISIBLE (-935 2892);
FORCEPROP 2 LAST SIG_NAME OCP_SFF_PRSNT01_R_N
J 0
(-1360 2860);
DISPLAY 0.553191 (-1360 2860);
PAINT WHITE (-1360 2860);
WIRE 16 -1 (-850 2850)(-850 2450);
WIRE 16 -1 (-400 2550)(-400 3025);
WIRE 16 -1 (-325 3025)(-400 3025);
WIRE 16 -1 (-325 3025)(-325 2950);
WIRE 16 -1 (-2700 2800)(-2025 2800);
FORCEPROP 0 LAST CDS_PHYS_NET_NAME OCP_SFF_PRSNT1_R_N
J 0
(-2110 2842);
PAINT MONO (-2110 2842);
DISPLAY INVISIBLE (-2110 2842);
FORCEPROP 2 LAST SIG_NAME OCP_SFF_PRSNT1_R_N
J 0
(-2660 2810);
DISPLAY 0.553191 (-2660 2810);
PAINT WHITE (-2660 2810);
WIRE 16 -1 (-2700 2900)(-2025 2900);
FORCEPROP 0 LAST CDS_PHYS_NET_NAME OCP_SFF_PRSNT0_R_N
J 0
(-2110 2942);
PAINT MONO (-2110 2942);
DISPLAY INVISIBLE (-2110 2942);
FORCEPROP 2 LAST SIG_NAME OCP_SFF_PRSNT0_R_N
J 0
(-2660 2910);
DISPLAY 0.553191 (-2660 2910);
PAINT WHITE (-2660 2910);
WIRE 16 -1 (-1725 3000)(-1725 3450);
WIRE 16 -1 (-1600 3450)(-1725 3450);
WIRE 16 -1 (-1600 3350)(-1600 3450);
WIRE 16 -1 (275 -575)(700 -575);
WIRE 16 -1 (275 -575)(275 275);
WIRE 16 -1 (275 275)(725 275);
FORCEPROP 0 LAST CDS_PHYS_NET_NAME OCP_SFF_PRSNT0_R_N
J 0
(1240 317);
PAINT MONO (1240 317);
DISPLAY INVISIBLE (1240 317);
WIRE 16 -1 (-100 275)(275 275);
FORCEPROP 2 LAST SIG_NAME OCP_V3_2_PRSNT_ALL_R_N
J 0
(-35 285);
DISPLAY 0.553191 (-35 285);
PAINT WHITE (-35 285);
WIRE 16 -1 (-2675 -200)(-2025 -200);
FORCEPROP 0 LAST CDS_PHYS_NET_NAME OCP_V3_2_PRSNT3_R_N
J 0
(-2135 -158);
PAINT MONO (-2135 -158);
DISPLAY INVISIBLE (-2135 -158);
FORCEPROP 2 LAST SIG_NAME OCP_V3_2_PRSNT3_R_N
J 0
(-2635 -190);
DISPLAY 0.553191 (-2635 -190);
PAINT WHITE (-2635 -190);
WIRE 16 -1 (-2675 -100)(-2025 -100);
FORCEPROP 0 LAST CDS_PHYS_NET_NAME OCP_V3_2_PRSNT2_R_N
J 0
(-2135 -58);
PAINT MONO (-2135 -58);
DISPLAY INVISIBLE (-2135 -58);
FORCEPROP 2 LAST SIG_NAME OCP_V3_2_PRSNT2_R_N
J 0
(-2635 -90);
DISPLAY 0.553191 (-2635 -90);
PAINT WHITE (-2635 -90);
WIRE 16 -1 (-2675 800)(-2025 800);
FORCEPROP 0 LAST CDS_PHYS_NET_NAME OCP_V3_2_PRSNT0_R_N
J 0
(-2135 842);
PAINT MONO (-2135 842);
DISPLAY INVISIBLE (-2135 842);
FORCEPROP 2 LAST SIG_NAME OCP_V3_2_PRSNT0_R_N
J 0
(-2635 810);
DISPLAY 0.553191 (-2635 810);
PAINT WHITE (-2635 810);
WIRE 16 -1 (-2675 700)(-2025 700);
FORCEPROP 0 LAST CDS_PHYS_NET_NAME OCP_V3_2_PRSNT1_R_N
J 0
(-2135 742);
PAINT MONO (-2135 742);
DISPLAY INVISIBLE (-2135 742);
FORCEPROP 2 LAST SIG_NAME OCP_V3_2_PRSNT1_R_N
J 0
(-2635 710);
DISPLAY 0.553191 (-2635 710);
PAINT WHITE (-2635 710);
WIRE 16 -1 (-2700 1900)(-2025 1900);
FORCEPROP 0 LAST CDS_PHYS_NET_NAME OCP_SFF_PRSNT3_R_N
J 0
(-2110 1942);
PAINT MONO (-2110 1942);
DISPLAY INVISIBLE (-2110 1942);
FORCEPROP 2 LAST SIG_NAME OCP_SFF_PRSNT3_R_N
J 0
(-2660 1910);
DISPLAY 0.553191 (-2660 1910);
PAINT WHITE (-2660 1910);
WIRE 16 -1 (-2700 2000)(-2025 2000);
FORCEPROP 0 LAST CDS_PHYS_NET_NAME OCP_SFF_PRSNT2_R_N
J 0
(-2110 2042);
PAINT MONO (-2110 2042);
DISPLAY INVISIBLE (-2110 2042);
FORCEPROP 2 LAST SIG_NAME OCP_SFF_PRSNT2_R_N
J 0
(-2660 2010);
DISPLAY 0.553191 (-2660 2010);
PAINT WHITE (-2660 2010);
WIRE 16 -1 (-150 -675)(700 -675);
FORCEPROP 2 LAST SIG_NAME OCP_SFF_RBT_ARB_IN_MUX2
J 0
(-135 -665);
DISPLAY 0.553191 (-135 -665);
PAINT WHITE (-135 -665);
WIRE 16 -1 (900 -675)(1875 -675);
FORCEPROP 2 LAST SIG_NAME OCP_SFF_RBT_ARB_IN_MUX2_R
J 0
(1115 -665);
DISPLAY 0.553191 (1115 -665);
PAINT WHITE (1115 -665);
WIRE 16 -1 (900 -575)(1875 -575);
FORCEPROP 2 LAST SIG_NAME OCP_V3_2_PRSNT_ALL_R3_N
J 0
(1115 -565);
DISPLAY 0.510638 (1115 -565);
PAINT WHITE (1115 -565);
WIRE 16 -1 (1900 175)(1275 175);
FORCEPROP 2 LAST SIG_NAME OCP_SFF_RBT_ARB_IN_MUX1
J 0
(1290 185);
DISPLAY 0.553191 (1290 185);
PAINT WHITE (1290 185);
WIRE 16 -1 (750 2300)(1725 2300);
FORCEPROP 2 LAST SIG_NAME OCP_SFF_RBT_ARB_IN_MUX2
J 0
(915 2310);
DISPLAY 0.553191 (915 2310);
PAINT WHITE (915 2310);
WIRE 16 -1 (925 2400)(1725 2400);
FORCEPROP 2 LAST SIG_NAME OCP_SFF_PRSNT_ALL_R1_N
J 0
(1065 2410);
DISPLAY 0.510638 (1065 2410);
PAINT WHITE (1065 2410);
WIRE 16 -1 (3325 -675)(2475 -675);
FORCEPROP 2 LAST SIG_NAME OCP_V3_2_RBT_ARB_IN
J 0
(2590 -665);
DISPLAY 0.680851 (2590 -665);
PAINT WHITE (2590 -665);
WIRE 16 -1 (3300 175)(2500 175);
FORCEPROP 2 LAST SIG_NAME OCP_V3_2_RBT_ARB_OUT
J 0
(2615 185);
DISPLAY 0.680851 (2615 185);
PAINT WHITE (2615 185);
WIRE 16 -1 (1525 -150)(1525 -50);
WIRE 16 -1 (1850 -50)(1525 -50);
WIRE 16 -1 (1850 -625)(1850 -50);
WIRE 16 -1 (1875 -625)(1850 -625);
WIRE 16 -1 (1675 2350)(1675 2975);
WIRE 16 -1 (1725 2350)(1675 2350);
WIRE 16 -1 (-1425 -150)(-850 -150);
FORCEPROP 0 LAST CDS_PHYS_NET_NAME OCP_SFF_PRSNT0_R_N
J 0
(-935 -108);
PAINT MONO (-935 -108);
DISPLAY INVISIBLE (-935 -108);
FORCEPROP 2 LAST SIG_NAME OCP_V3_2_PRSNT23_R_N
J 0
(-1385 -140);
DISPLAY 0.553191 (-1385 -140);
PAINT WHITE (-1385 -140);
WIRE 16 -1 (-850 -150)(-850 225);
WIRE 16 -1 (-850 225)(-700 225);
WIRE 16 -1 (-850 325)(-700 325);
WIRE 16 -1 (-1425 750)(-850 750);
FORCEPROP 0 LAST CDS_PHYS_NET_NAME OCP_SFF_PRSNT0_R_N
J 0
(-935 792);
PAINT MONO (-935 792);
DISPLAY INVISIBLE (-935 792);
FORCEPROP 2 LAST SIG_NAME OCP_V3_2_PRSNT01_R_N
J 0
(-1385 760);
DISPLAY 0.553191 (-1385 760);
PAINT WHITE (-1385 760);
WIRE 16 -1 (-850 750)(-850 325);
DOT 1 (-1600 3450);
DOT 1 (1325 2975);
DOT 1 (-325 3025);
DOT 1 (1350 2100);
DOT 1 (1525 775);
DOT 1 (1525 -50);
DOT 1 (175 2400);
DOT 1 (275 275);
DOT 1 (-1500 1350);
FORCENOTE
20210922 MODIFY FOR GT
(-3950 3775) 0;
DISPLAY LEFT (-3950 3775);
DISPLAY 2.510638 (-3950 3775);
PAINT PINK (-3950 3775);
QUIT
